# Altium SchDoc records: 07-FPGA.SchDoc
|HEADER=Protel for Windows - Schematic Capture Binary File Version 5.0|Weight=1351|MinorVersion=6
|RECORD=31|FontIdCount=6|Size1=10|FontName1=Times New Roman|Size2=8|FontName2=Arial|Size3=10|FontName3=Arial|Size4=12|Underline4=T|FontName4=Arial|Size5=11|FontName5=Arial|Size6=10|Underline6=T|FontName6=Times New Roman|UseMBCS=T|IsBOC=T|HotSpotGridOn=T|HotSpotGridSize=2|SheetStyle=12|SystemFont=3|BorderOn=T|SheetNumberSpaceSize=12|AreaColor=16317695|SnapGridOn=T|SnapGridSize=5|VisibleGridOn=T|VisibleGridSize=10|CustomX=2338|CustomX_Frac=58268|CustomY=1653|CustomY_Frac=54331|CustomXZones=8|CustomYZones=6|CustomMarginWidth=19|CustomMarginWidth_Frac=80000|ShowTemplateGraphics=T|TemplateFileName=C:\Users\<user>\Documents\Altium\AD20\Templates\Timecard.SchDot|Display_Unit=0
|RECORD=39|IsNotAccesible=T|OwnerPartId=-1|FileName=C:\Users\<user>\Documents\Altium\AD20\Templates\Timecard.SchDot
|RECORD=4|OwnerIndex=1|OwnerPartId=-1|Location.X=1594|Location.Y=39|Color=8388608|FontID=4|Text=timingcard.com|URL=http://timingcard.com
|RECORD=6|OwnerIndex=1|IndexInSheet=1|OwnerPartId=-1|LocationCount=2|X1=1680|Y1=35|X2=1576|Y2=35
|RECORD=4|OwnerIndex=1|IndexInSheet=2|OwnerPartId=-1|Location.X=1615|Location.Y=27|Justification=4|Color=16711680|FontID=5|Text==SheetNumber
|RECORD=4|OwnerIndex=1|IndexInSheet=3|OwnerPartId=-1|Location.X=1581|Location.X_Frac=42446|Location.Y=29|Location.Y_Frac=96838|Justification=3|FontID=2|Text=SHEET
|RECORD=4|OwnerIndex=1|IndexInSheet=4|OwnerPartId=-1|Location.X=1639|Location.X_Frac=42446|Location.Y=29|Location.Y_Frac=96838|Justification=3|FontID=2|Text=OF
|RECORD=6|OwnerIndex=1|IndexInSheet=5|OwnerPartId=-1|LineWidth=1|LocationCount=2|X1=1679|X1_Frac=42446|Y1=117|Y1_Frac=96838|X2=1576|Y2=118
|RECORD=4|OwnerIndex=1|IndexInSheet=6|OwnerPartId=-1|Location.X=1659|Location.Y=27|Justification=4|Color=16711680|FontID=5|Text==SheetTotal
|RECORD=30|OwnerIndex=1|IndexInSheet=7|OwnerPartId=-1|Location.X=1578|Location.Y=65|Corner.X=1673|Corner.X_Frac=88801|Corner.Y=115|KeepAspect=T|FileName=C:\Users\<user>\Desktop\Timecard Logo\TIMECARD.jpg
|RECORD=6|OwnerIndex=1|IndexInSheet=8|OwnerPartId=-1|LineWidth=1|LocationCount=2|X1=1576|X1_Frac=3162|Y1=117|Y1_Frac=42446|X2=1576|Y2=21
|RECORD=6|OwnerIndex=1|IndexInSheet=9|OwnerPartId=-1|LocationCount=2|X1=1680|Y1=51|X2=1576|Y2=51
|RECORD=4|OwnerIndex=1|IndexInSheet=10|OwnerPartId=-1|Location.X=1581|Location.X_Frac=42446|Location.Y=56|Location.Y_Frac=96838|Justification=3|FontID=2|Text=REV
|RECORD=4|OwnerIndex=1|IndexInSheet=11|OwnerPartId=-1|Location.X=1619|Location.Y=57|Justification=3|FontID=2|Text=DATE
|RECORD=6|OwnerIndex=1|IndexInSheet=12|OwnerPartId=-1|LocationCount=2|X1=1680|Y1=65|X2=1576|Y2=65
|RECORD=4|OwnerIndex=1|IndexInSheet=13|OwnerPartId=-1|Location.X=1605|Location.Y=58|Justification=4|Color=16711680|FontID=5|Text==ProjectRevision
|RECORD=4|OwnerIndex=1|IndexInSheet=14|OwnerPartId=-1|Location.X=1659|Location.Y=58|Justification=4|Color=16711680|FontID=5|Text==ProjectDate
|RECORD=41|IndexInSheet=1|OwnerPartId=-1|Location.X=21474|Location.X_Frac=83647|Location.Y=21464|Location.Y_Frac=83647|Color=8388608|FontID=1|IsHidden=T|Text=01910|Name=Customer
|RECORD=41|IndexInSheet=2|OwnerPartId=-1|Location.X=1000|Location.Y=10|Color=8388608|FontID=1|IsHidden=T|Text=*|Name=DocStatus
|RECORD=17|IndexInSheet=3|OwnerPartId=-1|ShowNetName=T|Location.X=410|Location.Y=1008|Orientation=1|Color=128|FontID=1|Text=+5.0V
|RECORD=22|IndexInSheet=4|OwnerPartId=-1|Location.X=460|Location.Y=938|Color=255|Orientation=1|Symbol=Thin Cross|IsActive=T|SuppressAll=T
|RECORD=22|IndexInSheet=5|OwnerPartId=-1|Location.X=460|Location.Y=928|Color=255|Orientation=1|Symbol=Thin Cross|IsActive=T|SuppressAll=T
|RECORD=22|IndexInSheet=6|OwnerPartId=-1|Location.X=460|Location.Y=918|Color=255|Orientation=1|Symbol=Thin Cross|IsActive=T|SuppressAll=T
|RECORD=22|IndexInSheet=7|OwnerPartId=-1|Location.X=460|Location.Y=908|Color=255|Orientation=1|Symbol=Thin Cross|IsActive=T|SuppressAll=T
|RECORD=22|IndexInSheet=8|OwnerPartId=-1|Location.X=460|Location.Y=718|Color=255|Orientation=1|Symbol=Thin Cross|IsActive=T|SuppressAll=T
|RECORD=22|IndexInSheet=9|OwnerPartId=-1|Location.X=460|Location.Y=708|Color=255|Orientation=1|Symbol=Thin Cross|IsActive=T|SuppressAll=T
|RECORD=22|IndexInSheet=10|OwnerPartId=-1|Location.X=460|Location.Y=598|Color=255|Orientation=1|Symbol=Thin Cross|IsActive=T|SuppressAll=T
|RECORD=17|IndexInSheet=11|OwnerPartId=-1|Style=4|ShowNetName=T|Location.X=410|Location.Y=568|Orientation=3|Color=128|FontID=1|Text=GND
|RECORD=17|IndexInSheet=12|OwnerPartId=-1|ShowNetName=T|Location.X=330|Location.Y=658|Orientation=2|Color=255|FontID=1|Text=KEY2|IsCrossSheetConnector=T
|RECORD=17|IndexInSheet=13|OwnerPartId=-1|ShowNetName=T|Location.X=330|Location.Y=638|Orientation=2|Color=255|FontID=1|Text=LED4|IsCrossSheetConnector=T
|RECORD=17|IndexInSheet=14|OwnerPartId=-1|ShowNetName=T|Location.X=330|Location.Y=628|Orientation=2|Color=255|FontID=1|Text=LED3|IsCrossSheetConnector=T
|RECORD=17|IndexInSheet=15|OwnerPartId=-1|ShowNetName=T|Location.X=330|Location.Y=618|Orientation=2|Color=255|FontID=1|Text=LED2|IsCrossSheetConnector=T
|RECORD=17|IndexInSheet=16|OwnerPartId=-1|ShowNetName=T|Location.X=330|Location.Y=608|Orientation=2|Color=255|FontID=1|Text=LED1|IsCrossSheetConnector=T
|RECORD=17|IndexInSheet=17|OwnerPartId=-1|ShowNetName=T|Location.X=600|Location.Y=1008|Orientation=1|Color=128|FontID=1|Text=+5.0V
|RECORD=22|IndexInSheet=18|OwnerPartId=-1|Location.X=580|Location.Y=938|Color=255|Orientation=1|Symbol=Thin Cross|IsActive=T|SuppressAll=T
|RECORD=22|IndexInSheet=19|OwnerPartId=-1|Location.X=580|Location.Y=928|Color=255|Orientation=1|Symbol=Thin Cross|IsActive=T|SuppressAll=T
|RECORD=22|IndexInSheet=20|OwnerPartId=-1|Location.X=580|Location.Y=738|Color=255|Orientation=1|Symbol=Thin Cross|IsActive=T|SuppressAll=T
|RECORD=22|IndexInSheet=21|OwnerPartId=-1|Location.X=580|Location.Y=668|Color=255|Orientation=1|Symbol=Thin Cross|IsActive=T|SuppressAll=T
|RECORD=22|IndexInSheet=22|OwnerPartId=-1|Location.X=580|Location.Y=658|Color=255|Orientation=1|Symbol=Thin Cross|IsActive=T|SuppressAll=T
|RECORD=22|IndexInSheet=23|OwnerPartId=-1|Location.X=580|Location.Y=638|Color=255|Orientation=1|Symbol=Thin Cross|IsActive=T|SuppressAll=T
|RECORD=22|IndexInSheet=24|OwnerPartId=-1|Location.X=580|Location.Y=628|Color=255|Orientation=1|Symbol=Thin Cross|IsActive=T|SuppressAll=T
|RECORD=22|IndexInSheet=25|OwnerPartId=-1|Location.X=580|Location.Y=618|Color=255|Orientation=1|Symbol=Thin Cross|IsActive=T|SuppressAll=T
|RECORD=22|IndexInSheet=26|OwnerPartId=-1|Location.X=580|Location.Y=608|Color=255|Orientation=1|Symbol=Thin Cross|IsActive=T|SuppressAll=T
|RECORD=22|IndexInSheet=27|OwnerPartId=-1|Location.X=580|Location.Y=598|Color=255|Orientation=1|Symbol=Thin Cross|IsActive=T|SuppressAll=T
|RECORD=17|IndexInSheet=28|OwnerPartId=-1|Style=4|ShowNetName=T|Location.X=600|Location.Y=568|Orientation=3|Color=128|FontID=1|Text=GND
|RECORD=17|IndexInSheet=29|OwnerPartId=-1|ShowNetName=T|Location.X=640|Location.Y=888|Color=255|FontID=1|Text=GPS1_RST|IsCrossSheetConnector=T
|RECORD=17|IndexInSheet=30|OwnerPartId=-1|ShowNetName=T|Location.X=640|Location.Y=838|Color=255|FontID=1|Text=GPS1_TP1|IsCrossSheetConnector=T
|RECORD=17|IndexInSheet=31|OwnerPartId=-1|ShowNetName=T|Location.X=640|Location.Y=828|Color=255|FontID=1|Text=GPS1_TP2|IsCrossSheetConnector=T
|RECORD=17|IndexInSheet=32|OwnerPartId=-1|Style=4|ShowNetName=T|Location.X=1130|Location.Y=568|Orientation=3|Color=128|FontID=1|Text=GND
|RECORD=17|IndexInSheet=33|OwnerPartId=-1|ShowNetName=T|Location.X=1060|Location.Y=598|Orientation=2|Color=255|FontID=1|Text=GPS1_RX|IsCrossSheetConnector=T
|RECORD=17|IndexInSheet=34|OwnerPartId=-1|ShowNetName=T|Location.X=1060|Location.Y=818|Orientation=2|Color=255|FontID=1|Text=MAC_ALARM|IsCrossSheetConnector=T
|RECORD=17|IndexInSheet=35|OwnerPartId=-1|ShowNetName=T|Location.X=1060|Location.Y=808|Orientation=2|Color=255|FontID=1|Text=MAC_BITE|IsCrossSheetConnector=T
|RECORD=17|IndexInSheet=36|OwnerPartId=-1|ShowNetName=T|Location.X=1060|Location.Y=828|Orientation=2|Color=255|FontID=1|Text=MAC_FREQ_CTRL|IsCrossSheetConnector=T
|RECORD=17|IndexInSheet=37|OwnerPartId=-1|ShowNetName=T|Location.X=1060|Location.Y=758|Orientation=2|Color=255|FontID=1|Text=FPGA_MAC_PPS_IN0-|IsCrossSheetConnector=T
|RECORD=17|IndexInSheet=38|OwnerPartId=-1|ShowNetName=T|Location.X=1060|Location.Y=728|Orientation=2|Color=255|FontID=1|Text=FPGA_MAC_PPS_IN1-|IsCrossSheetConnector=T
|RECORD=17|IndexInSheet=39|OwnerPartId=-1|ShowNetName=T|Location.X=1060|Location.Y=778|Orientation=2|Color=255|FontID=1|Text=FPGA_MAC_PPS_OUT-|IsCrossSheetConnector=T
|RECORD=17|IndexInSheet=40|OwnerPartId=-1|ShowNetName=T|Location.X=1060|Location.Y=938|Orientation=2|Color=255|FontID=1|Text=MAC_RF_OUT|IsCrossSheetConnector=T
|RECORD=17|IndexInSheet=41|OwnerPartId=-1|ShowNetName=T|Location.X=1060|Location.Y=688|Orientation=2|Color=255|FontID=1|Text=SDA|IsCrossSheetConnector=T
|RECORD=17|IndexInSheet=42|OwnerPartId=-1|ShowNetName=T|Location.X=1060|Location.Y=658|Orientation=2|Color=255|FontID=1|Text=SCL|IsCrossSheetConnector=T
|RECORD=17|IndexInSheet=43|OwnerPartId=-1|Style=4|ShowNetName=T|Location.X=1320|Location.Y=568|Orientation=3|Color=128|FontID=1|Text=GND
|RECORD=17|IndexInSheet=44|OwnerPartId=-1|ShowNetName=T|Location.X=1350|Location.Y=598|Color=255|FontID=1|Text=GPS1_TX|IsCrossSheetConnector=T
|RECORD=17|IndexInSheet=45|OwnerPartId=-1|ShowNetName=T|Location.X=1350|Location.Y=858|Color=255|FontID=1|Text=MAC_RX|IsCrossSheetConnector=T
|RECORD=17|IndexInSheet=46|OwnerPartId=-1|ShowNetName=T|Location.X=1350|Location.Y=868|Color=255|FontID=1|Text=MAC_TX|IsCrossSheetConnector=T
|RECORD=17|IndexInSheet=47|OwnerPartId=-1|ShowNetName=T|Location.X=1350|Location.Y=638|Color=255|FontID=1|Text=MAC_USB+|IsCrossSheetConnector=T
|RECORD=17|IndexInSheet=48|OwnerPartId=-1|ShowNetName=T|Location.X=1350|Location.Y=628|Color=255|FontID=1|Text=MAC_USB-|IsCrossSheetConnector=T
|RECORD=17|IndexInSheet=49|OwnerPartId=-1|ShowNetName=T|Location.X=1350|Location.Y=958|Color=255|FontID=1|Text=MAC_USB_PWR|IsCrossSheetConnector=T
|RECORD=17|IndexInSheet=50|OwnerPartId=-1|Style=4|ShowNetName=T|Location.X=400|Location.Y=68|Orientation=3|Color=128|FontID=1|Text=GND
|RECORD=22|IndexInSheet=51|OwnerPartId=-1|Location.X=460|Location.Y=128|Color=255|Orientation=1|Symbol=Thin Cross|IsActive=T|SuppressAll=T
|RECORD=17|IndexInSheet=52|OwnerPartId=-1|ShowNetName=T|Location.X=320|Location.Y=398|Orientation=2|Color=255|FontID=1|Text=PCIE_PERST|IsCrossSheetConnector=T
|RECORD=17|IndexInSheet=53|OwnerPartId=-1|ShowNetName=T|Location.X=320|Location.Y=388|Orientation=2|Color=255|FontID=1|Text=KEY1|IsCrossSheetConnector=T
|RECORD=17|IndexInSheet=54|OwnerPartId=-1|ShowNetName=T|Location.X=320|Location.Y=118|Orientation=2|Color=255|FontID=1|Text=FPGA_TCK|IsCrossSheetConnector=T
|RECORD=17|IndexInSheet=55|OwnerPartId=-1|ShowNetName=T|Location.X=320|Location.Y=108|Orientation=2|Color=255|FontID=1|Text=FPGA_TDO|IsCrossSheetConnector=T
|RECORD=17|IndexInSheet=56|OwnerPartId=-1|Style=4|ShowNetName=T|Location.X=620|Location.Y=68|Orientation=3|Color=128|FontID=1|Text=GND
|RECORD=22|IndexInSheet=57|OwnerPartId=-1|Location.X=580|Location.Y=128|Color=255|Orientation=1|Symbol=Thin Cross|IsActive=T|SuppressAll=T
|RECORD=17|IndexInSheet=58|OwnerPartId=-1|ShowNetName=T|Location.X=690|Location.Y=118|Color=255|FontID=1|Text=FPGA_TDI|IsCrossSheetConnector=T
|RECORD=17|IndexInSheet=59|OwnerPartId=-1|ShowNetName=T|Location.X=690|Location.Y=108|Color=255|FontID=1|Text=FPGA_TMS|IsCrossSheetConnector=T
|RECORD=22|IndexInSheet=60|OwnerPartId=-1|Location.X=1160|Location.Y=498|Color=255|Orientation=1|Symbol=Thin Cross|IsActive=T|SuppressAll=T
|RECORD=22|IndexInSheet=61|OwnerPartId=-1|Location.X=1160|Location.Y=488|Color=255|Orientation=1|Symbol=Thin Cross|IsActive=T|SuppressAll=T
|RECORD=22|IndexInSheet=62|OwnerPartId=-1|Location.X=1160|Location.Y=478|Color=255|Orientation=1|Symbol=Thin Cross|IsActive=T|SuppressAll=T
|RECORD=22|IndexInSheet=63|OwnerPartId=-1|Location.X=1160|Location.Y=468|Color=255|Orientation=1|Symbol=Thin Cross|IsActive=T|SuppressAll=T
|RECORD=22|IndexInSheet=64|OwnerPartId=-1|Location.X=1160|Location.Y=448|Color=255|Orientation=1|Symbol=Thin Cross|IsActive=T|SuppressAll=T
|RECORD=22|IndexInSheet=65|OwnerPartId=-1|Location.X=1160|Location.Y=438|Color=255|Orientation=1|Symbol=Thin Cross|IsActive=T|SuppressAll=T
|RECORD=22|IndexInSheet=66|OwnerPartId=-1|Location.X=1160|Location.Y=108|Color=255|Orientation=1|Symbol=Thin Cross|IsActive=T|SuppressAll=T
|RECORD=17|IndexInSheet=67|OwnerPartId=-1|Style=4|ShowNetName=T|Location.X=1110|Location.Y=78|Orientation=3|Color=128|FontID=1|Text=GND
|RECORD=17|IndexInSheet=68|OwnerPartId=-1|ShowNetName=T|Location.X=1060|Location.Y=418|Orientation=2|Color=255|FontID=1|Text=PCIE_TX3_P|IsCrossSheetConnector=T
|RECORD=17|IndexInSheet=69|OwnerPartId=-1|ShowNetName=T|Location.X=1060|Location.Y=408|Orientation=2|Color=255|FontID=1|Text=PCIE_TX3_N|IsCrossSheetConnector=T
|RECORD=17|IndexInSheet=70|OwnerPartId=-1|ShowNetName=T|Location.X=1060|Location.Y=388|Orientation=2|Color=255|FontID=1|Text=PCIE_RX3_P|IsCrossSheetConnector=T
|RECORD=17|IndexInSheet=71|OwnerPartId=-1|ShowNetName=T|Location.X=1060|Location.Y=378|Orientation=2|Color=255|FontID=1|Text=PCIE_RX3_N|IsCrossSheetConnector=T
|RECORD=17|IndexInSheet=72|OwnerPartId=-1|ShowNetName=T|Location.X=1060|Location.Y=358|Orientation=2|Color=255|FontID=1|Text=PCIE_TX0_P|IsCrossSheetConnector=T
|RECORD=17|IndexInSheet=73|OwnerPartId=-1|ShowNetName=T|Location.X=1060|Location.Y=348|Orientation=2|Color=255|FontID=1|Text=PCIE_TX0_N|IsCrossSheetConnector=T
|RECORD=17|IndexInSheet=74|OwnerPartId=-1|ShowNetName=T|Location.X=1060|Location.Y=328|Orientation=2|Color=255|FontID=1|Text=PCIE_RX0_P|IsCrossSheetConnector=T
|RECORD=17|IndexInSheet=75|OwnerPartId=-1|ShowNetName=T|Location.X=1060|Location.Y=318|Orientation=2|Color=255|FontID=1|Text=PCIE_RX0_N|IsCrossSheetConnector=T
|RECORD=43|IndexInSheet=76|OwnerPartId=-1|Location.X=1070|Location.Y=418|Color=255|Name=DIFFPAIR
|RECORD=41|OwnerIndex=92|OwnerPartId=-1|Location.X=1070|Location.Y=418|Color=8388608|FontID=1|IsHidden=T|Text=True|Name=DifferentialPair
|RECORD=43|IndexInSheet=77|OwnerPartId=-1|Location.X=1070|Location.Y=408|Color=255|Name=DIFFPAIR
|RECORD=41|OwnerIndex=94|OwnerPartId=-1|Location.X=1070|Location.Y=408|Color=8388608|FontID=1|IsHidden=T|Text=True|Name=DifferentialPair
|RECORD=43|IndexInSheet=78|OwnerPartId=-1|Location.X=1070|Location.Y=388|Color=255|Name=DIFFPAIR
|RECORD=41|OwnerIndex=96|OwnerPartId=-1|Location.X=1070|Location.Y=388|Color=8388608|FontID=1|IsHidden=T|Text=True|Name=DifferentialPair
|RECORD=43|IndexInSheet=79|OwnerPartId=-1|Location.X=1070|Location.Y=378|Color=255|Name=DIFFPAIR
|RECORD=41|OwnerIndex=98|OwnerPartId=-1|Location.X=1070|Location.Y=378|Color=8388608|FontID=1|IsHidden=T|Text=True|Name=DifferentialPair
|RECORD=43|IndexInSheet=80|OwnerPartId=-1|Location.X=1070|Location.Y=358|Color=255|Name=DIFFPAIR
|RECORD=41|OwnerIndex=100|OwnerPartId=-1|Location.X=1070|Location.Y=358|Color=8388608|FontID=1|IsHidden=T|Text=True|Name=DifferentialPair
|RECORD=43|IndexInSheet=81|OwnerPartId=-1|Location.X=1070|Location.Y=348|Color=255|Name=DIFFPAIR
|RECORD=41|OwnerIndex=102|OwnerPartId=-1|Location.X=1070|Location.Y=348|Color=8388608|FontID=1|IsHidden=T|Text=True|Name=DifferentialPair
|RECORD=43|IndexInSheet=82|OwnerPartId=-1|Location.X=1070|Location.Y=328|Color=255|Name=DIFFPAIR
|RECORD=41|OwnerIndex=104|OwnerPartId=-1|Location.X=1070|Location.Y=328|Color=8388608|FontID=1|IsHidden=T|Text=True|Name=DifferentialPair
|RECORD=43|IndexInSheet=83|OwnerPartId=-1|Location.X=1070|Location.Y=318|Color=255|Name=DIFFPAIR
|RECORD=41|OwnerIndex=106|OwnerPartId=-1|Location.X=1070|Location.Y=318|Color=8388608|FontID=1|IsHidden=T|Text=True|Name=DifferentialPair
|RECORD=22|IndexInSheet=84|OwnerPartId=-1|Location.X=1280|Location.Y=498|Color=255|Orientation=1|Symbol=Thin Cross|IsActive=T|SuppressAll=T
|RECORD=22|IndexInSheet=85|OwnerPartId=-1|Location.X=1280|Location.Y=488|Color=255|Orientation=1|Symbol=Thin Cross|IsActive=T|SuppressAll=T
|RECORD=22|IndexInSheet=86|OwnerPartId=-1|Location.X=1280|Location.Y=478|Color=255|Orientation=1|Symbol=Thin Cross|IsActive=T|SuppressAll=T
|RECORD=22|IndexInSheet=87|OwnerPartId=-1|Location.X=1280|Location.Y=468|Color=255|Orientation=1|Symbol=Thin Cross|IsActive=T|SuppressAll=T
|RECORD=22|IndexInSheet=88|OwnerPartId=-1|Location.X=1280|Location.Y=108|Color=255|Orientation=1|Symbol=Thin Cross|IsActive=T|SuppressAll=T
|RECORD=17|IndexInSheet=89|OwnerPartId=-1|Style=4|ShowNetName=T|Location.X=1310|Location.Y=78|Orientation=3|Color=128|FontID=1|Text=GND
|RECORD=17|IndexInSheet=90|OwnerPartId=-1|ShowNetName=T|Location.X=1360|Location.Y=448|Color=255|FontID=1|Text=PCIE_TX2_P|IsCrossSheetConnector=T
|RECORD=17|IndexInSheet=91|OwnerPartId=-1|ShowNetName=T|Location.X=1360|Location.Y=438|Color=255|FontID=1|Text=PCIE_TX2_N|IsCrossSheetConnector=T
|RECORD=17|IndexInSheet=92|OwnerPartId=-1|ShowNetName=T|Location.X=1360|Location.Y=418|Color=255|FontID=1|Text=PCIE_RX2_P|IsCrossSheetConnector=T
|RECORD=17|IndexInSheet=93|OwnerPartId=-1|ShowNetName=T|Location.X=1360|Location.Y=408|Color=255|FontID=1|Text=PCIE_RX2_N|IsCrossSheetConnector=T
|RECORD=17|IndexInSheet=94|OwnerPartId=-1|ShowNetName=T|Location.X=1360|Location.Y=388|Color=255|FontID=1|Text=PCIE_TX1_P|IsCrossSheetConnector=T
|RECORD=17|IndexInSheet=95|OwnerPartId=-1|ShowNetName=T|Location.X=1360|Location.Y=378|Color=255|FontID=1|Text=PCIE_TX1_N|IsCrossSheetConnector=T
|RECORD=17|IndexInSheet=96|OwnerPartId=-1|ShowNetName=T|Location.X=1360|Location.Y=358|Color=255|FontID=1|Text=PCIE_RX1_P|IsCrossSheetConnector=T
|RECORD=17|IndexInSheet=97|OwnerPartId=-1|ShowNetName=T|Location.X=1360|Location.Y=348|Color=255|FontID=1|Text=PCIE_RX1_N|IsCrossSheetConnector=T
|RECORD=17|IndexInSheet=98|OwnerPartId=-1|ShowNetName=T|Location.X=1360|Location.Y=328|Color=255|FontID=1|Text=PCIE_CLK_P|IsCrossSheetConnector=T
|RECORD=17|IndexInSheet=99|OwnerPartId=-1|ShowNetName=T|Location.X=1360|Location.Y=318|Color=255|FontID=1|Text=PCIE_CLK_N|IsCrossSheetConnector=T
|RECORD=43|IndexInSheet=100|OwnerPartId=-1|Location.X=1330|Location.Y=448|Color=255|Name=DIFFPAIR
|RECORD=41|OwnerIndex=124|OwnerPartId=-1|Location.X=1330|Location.Y=448|Color=8388608|FontID=1|IsHidden=T|Text=True|Name=DifferentialPair
|RECORD=43|IndexInSheet=101|OwnerPartId=-1|Location.X=1330|Location.Y=438|Color=255|Name=DIFFPAIR
|RECORD=41|OwnerIndex=126|OwnerPartId=-1|Location.X=1330|Location.Y=438|Color=8388608|FontID=1|IsHidden=T|Text=True|Name=DifferentialPair
|RECORD=43|IndexInSheet=102|OwnerPartId=-1|Location.X=1330|Location.Y=418|Color=255|Name=DIFFPAIR
|RECORD=41|OwnerIndex=128|OwnerPartId=-1|Location.X=1330|Location.Y=418|Color=8388608|FontID=1|IsHidden=T|Text=True|Name=DifferentialPair
|RECORD=43|IndexInSheet=103|OwnerPartId=-1|Location.X=1330|Location.Y=408|Color=255|Name=DIFFPAIR
|RECORD=41|OwnerIndex=130|OwnerPartId=-1|Location.X=1330|Location.Y=408|Color=8388608|FontID=1|IsHidden=T|Text=True|Name=DifferentialPair
|RECORD=43|IndexInSheet=104|OwnerPartId=-1|Location.X=1330|Location.Y=388|Color=255|Name=DIFFPAIR
|RECORD=41|OwnerIndex=132|OwnerPartId=-1|Location.X=1330|Location.Y=388|Color=8388608|FontID=1|IsHidden=T|Text=True|Name=DifferentialPair
|RECORD=43|IndexInSheet=105|OwnerPartId=-1|Location.X=1330|Location.Y=378|Color=255|Name=DIFFPAIR
|RECORD=41|OwnerIndex=134|OwnerPartId=-1|Location.X=1330|Location.Y=378|Color=8388608|FontID=1|IsHidden=T|Text=True|Name=DifferentialPair
|RECORD=43|IndexInSheet=106|OwnerPartId=-1|Location.X=1330|Location.Y=358|Color=255|Name=DIFFPAIR
|RECORD=41|OwnerIndex=136|OwnerPartId=-1|Location.X=1330|Location.Y=358|Color=8388608|FontID=1|IsHidden=T|Text=True|Name=DifferentialPair
|RECORD=43|IndexInSheet=107|OwnerPartId=-1|Location.X=1330|Location.Y=348|Color=255|Name=DIFFPAIR
|RECORD=41|OwnerIndex=138|OwnerPartId=-1|Location.X=1330|Location.Y=348|Color=8388608|FontID=1|IsHidden=T|Text=True|Name=DifferentialPair
|RECORD=43|IndexInSheet=108|OwnerPartId=-1|Location.X=1330|Location.Y=328|Color=255|Name=DIFFPAIR
|RECORD=41|OwnerIndex=140|OwnerPartId=-1|Location.X=1330|Location.Y=328|Color=8388608|FontID=1|IsHidden=T|Text=True|Name=DifferentialPair
|RECORD=43|IndexInSheet=109|OwnerPartId=-1|Location.X=1330|Location.Y=318|Color=255|Name=DIFFPAIR
|RECORD=41|OwnerIndex=142|OwnerPartId=-1|Location.X=1330|Location.Y=318|Color=8388608|FontID=1|IsHidden=T|Text=True|Name=DifferentialPair
|RECORD=22|IndexInSheet=110|OwnerPartId=-1|Location.X=460|Location.Y=838|Color=255|Orientation=1|Symbol=Thin Cross|IsActive=T|SuppressAll=T
|RECORD=22|IndexInSheet=111|OwnerPartId=-1|Location.X=460|Location.Y=828|Color=255|Orientation=1|Symbol=Thin Cross|IsActive=T|SuppressAll=T
|RECORD=22|IndexInSheet=112|OwnerPartId=-1|Location.X=460|Location.Y=808|Color=255|Orientation=1|Symbol=Thin Cross|IsActive=T|SuppressAll=T
|RECORD=22|IndexInSheet=113|OwnerPartId=-1|Location.X=460|Location.Y=788|Color=255|Orientation=1|Symbol=Thin Cross|IsActive=T|SuppressAll=T
|RECORD=22|IndexInSheet=114|OwnerPartId=-1|Location.X=460|Location.Y=758|Color=255|Orientation=1|Symbol=Thin Cross|IsActive=T|SuppressAll=T
|RECORD=22|IndexInSheet=115|OwnerPartId=-1|Location.X=460|Location.Y=738|Color=255|Orientation=1|Symbol=Thin Cross|IsActive=T|SuppressAll=T
|RECORD=22|IndexInSheet=116|OwnerPartId=-1|Location.X=460|Location.Y=728|Color=255|Orientation=1|Symbol=Thin Cross|IsActive=T|SuppressAll=T
|RECORD=22|IndexInSheet=117|OwnerPartId=-1|Location.X=460|Location.Y=688|Color=255|Orientation=1|Symbol=Thin Cross|IsActive=T|SuppressAll=T
|RECORD=22|IndexInSheet=118|OwnerPartId=-1|Location.X=460|Location.Y=678|Color=255|Orientation=1|Symbol=Thin Cross|IsActive=T|SuppressAll=T
|RECORD=22|IndexInSheet=119|OwnerPartId=-1|Location.X=460|Location.Y=668|Color=255|Orientation=1|Symbol=Thin Cross|IsActive=T|SuppressAll=T
|RECORD=22|IndexInSheet=120|OwnerPartId=-1|Location.X=460|Location.Y=588|Color=255|Orientation=1|Symbol=Thin Cross|IsActive=T|SuppressAll=T
|RECORD=22|IndexInSheet=121|OwnerPartId=-1|Location.X=460|Location.Y=578|Color=255|Orientation=1|Symbol=Thin Cross|IsActive=T|SuppressAll=T
|RECORD=22|IndexInSheet=122|OwnerPartId=-1|Location.X=580|Location.Y=588|Color=255|Orientation=1|Symbol=Thin Cross|IsActive=T|SuppressAll=T
|RECORD=22|IndexInSheet=123|OwnerPartId=-1|Location.X=580|Location.Y=578|Color=255|Orientation=1|Symbol=Thin Cross|IsActive=T|SuppressAll=T
|RECORD=22|IndexInSheet=124|OwnerPartId=-1|Location.X=580|Location.Y=708|Color=255|Orientation=1|Symbol=Thin Cross|IsActive=T|SuppressAll=T
|RECORD=22|IndexInSheet=125|OwnerPartId=-1|Location.X=580|Location.Y=788|Color=255|Orientation=1|Symbol=Thin Cross|IsActive=T|SuppressAll=T
|RECORD=22|IndexInSheet=126|OwnerPartId=-1|Location.X=580|Location.Y=808|Color=255|Orientation=1|Symbol=Thin Cross|IsActive=T|SuppressAll=T
|RECORD=22|IndexInSheet=127|OwnerPartId=-1|Location.X=580|Location.Y=818|Color=255|Orientation=1|Symbol=Thin Cross|IsActive=T|SuppressAll=T
|RECORD=22|IndexInSheet=128|OwnerPartId=-1|Location.X=580|Location.Y=858|Color=255|Orientation=1|Symbol=Thin Cross|IsActive=T|SuppressAll=T
|RECORD=22|IndexInSheet=129|OwnerPartId=-1|Location.X=580|Location.Y=868|Color=255|Orientation=1|Symbol=Thin Cross|IsActive=T|SuppressAll=T
|RECORD=22|IndexInSheet=130|OwnerPartId=-1|Location.X=580|Location.Y=878|Color=255|Orientation=1|Symbol=Thin Cross|IsActive=T|SuppressAll=T
|RECORD=22|IndexInSheet=131|OwnerPartId=-1|Location.X=580|Location.Y=908|Color=255|Orientation=1|Symbol=Thin Cross|IsActive=T|SuppressAll=T
|RECORD=22|IndexInSheet=132|OwnerPartId=-1|Location.X=580|Location.Y=918|Color=255|Orientation=1|Symbol=Thin Cross|IsActive=T|SuppressAll=T
|RECORD=22|IndexInSheet=133|OwnerPartId=-1|Location.X=1170|Location.Y=958|Color=255|Orientation=1|Symbol=Thin Cross|IsActive=T|SuppressAll=T
|RECORD=22|IndexInSheet=134|OwnerPartId=-1|Location.X=1290|Location.Y=938|Color=255|Orientation=1|Symbol=Thin Cross|IsActive=T|SuppressAll=T
|RECORD=22|IndexInSheet=135|OwnerPartId=-1|Location.X=1290|Location.Y=928|Color=255|Orientation=1|Symbol=Thin Cross|IsActive=T|SuppressAll=T
|RECORD=22|IndexInSheet=136|OwnerPartId=-1|Location.X=1290|Location.Y=888|Color=255|Orientation=1|Symbol=Thin Cross|IsActive=T|SuppressAll=T
|RECORD=22|IndexInSheet=137|OwnerPartId=-1|Location.X=1290|Location.Y=878|Color=255|Orientation=1|Symbol=Thin Cross|IsActive=T|SuppressAll=T
|RECORD=22|IndexInSheet=138|OwnerPartId=-1|Location.X=1290|Location.Y=838|Color=255|Orientation=1|Symbol=Thin Cross|IsActive=T|SuppressAll=T
|RECORD=22|IndexInSheet=139|OwnerPartId=-1|Location.X=1290|Location.Y=818|Color=255|Orientation=1|Symbol=Thin Cross|IsActive=T|SuppressAll=T
|RECORD=22|IndexInSheet=140|OwnerPartId=-1|Location.X=1290|Location.Y=808|Color=255|Orientation=1|Symbol=Thin Cross|IsActive=T|SuppressAll=T
|RECORD=22|IndexInSheet=141|OwnerPartId=-1|Location.X=1290|Location.Y=788|Color=255|Orientation=1|Symbol=Thin Cross|IsActive=T|SuppressAll=T
|RECORD=22|IndexInSheet=142|OwnerPartId=-1|Location.X=1290|Location.Y=778|Color=255|Orientation=1|Symbol=Thin Cross|IsActive=T|SuppressAll=T
|RECORD=22|IndexInSheet=143|OwnerPartId=-1|Location.X=1290|Location.Y=778|Color=255|Orientation=1|Symbol=Thin Cross|IsActive=T|SuppressAll=T
|RECORD=22|IndexInSheet=144|OwnerPartId=-1|Location.X=1290|Location.Y=768|Color=255|Orientation=1|Symbol=Thin Cross|IsActive=T|SuppressAll=T
|RECORD=22|IndexInSheet=145|OwnerPartId=-1|Location.X=1290|Location.Y=758|Color=255|Orientation=1|Symbol=Thin Cross|IsActive=T|SuppressAll=T
|RECORD=22|IndexInSheet=146|OwnerPartId=-1|Location.X=1290|Location.Y=738|Color=255|Orientation=1|Symbol=Thin Cross|IsActive=T|SuppressAll=T
|RECORD=22|IndexInSheet=147|OwnerPartId=-1|Location.X=1290|Location.Y=728|Color=255|Orientation=1|Symbol=Thin Cross|IsActive=T|SuppressAll=T
|RECORD=22|IndexInSheet=148|OwnerPartId=-1|Location.X=1290|Location.Y=718|Color=255|Orientation=1|Symbol=Thin Cross|IsActive=T|SuppressAll=T
|RECORD=22|IndexInSheet=149|OwnerPartId=-1|Location.X=1290|Location.Y=708|Color=255|Orientation=1|Symbol=Thin Cross|IsActive=T|SuppressAll=T
|RECORD=22|IndexInSheet=150|OwnerPartId=-1|Location.X=1290|Location.Y=688|Color=255|Orientation=1|Symbol=Thin Cross|IsActive=T|SuppressAll=T
|RECORD=22|IndexInSheet=151|OwnerPartId=-1|Location.X=1280|Location.Y=428|Color=255|Orientation=1|Symbol=Thin Cross|IsActive=T|SuppressAll=T
|RECORD=22|IndexInSheet=152|OwnerPartId=-1|Location.X=1280|Location.Y=398|Color=255|Orientation=1|Symbol=Thin Cross|IsActive=T|SuppressAll=T
|RECORD=22|IndexInSheet=153|OwnerPartId=-1|Location.X=1280|Location.Y=368|Color=255|Orientation=1|Symbol=Thin Cross|IsActive=T|SuppressAll=T
|RECORD=22|IndexInSheet=154|OwnerPartId=-1|Location.X=1280|Location.Y=338|Color=255|Orientation=1|Symbol=Thin Cross|IsActive=T|SuppressAll=T
|RECORD=22|IndexInSheet=155|OwnerPartId=-1|Location.X=1280|Location.Y=298|Color=255|Orientation=1|Symbol=Thin Cross|IsActive=T|SuppressAll=T
|RECORD=22|IndexInSheet=156|OwnerPartId=-1|Location.X=1280|Location.Y=288|Color=255|Orientation=1|Symbol=Thin Cross|IsActive=T|SuppressAll=T
|RECORD=22|IndexInSheet=157|OwnerPartId=-1|Location.X=1280|Location.Y=278|Color=255|Orientation=1|Symbol=Thin Cross|IsActive=T|SuppressAll=T
|RECORD=22|IndexInSheet=158|OwnerPartId=-1|Location.X=1280|Location.Y=268|Color=255|Orientation=1|Symbol=Thin Cross|IsActive=T|SuppressAll=T
|RECORD=22|IndexInSheet=159|OwnerPartId=-1|Location.X=1160|Location.Y=298|Color=255|Orientation=1|Symbol=Thin Cross|IsActive=T|SuppressAll=T
|RECORD=22|IndexInSheet=160|OwnerPartId=-1|Location.X=1160|Location.Y=288|Color=255|Orientation=1|Symbol=Thin Cross|IsActive=T|SuppressAll=T
|RECORD=22|IndexInSheet=161|OwnerPartId=-1|Location.X=1160|Location.Y=278|Color=255|Orientation=1|Symbol=Thin Cross|IsActive=T|SuppressAll=T
|RECORD=22|IndexInSheet=162|OwnerPartId=-1|Location.X=1160|Location.Y=268|Color=255|Orientation=1|Symbol=Thin Cross|IsActive=T|SuppressAll=T
|RECORD=22|IndexInSheet=163|OwnerPartId=-1|Location.X=1160|Location.Y=248|Color=255|Orientation=1|Symbol=Thin Cross|IsActive=T|SuppressAll=T
|RECORD=22|IndexInSheet=164|OwnerPartId=-1|Location.X=1160|Location.Y=238|Color=255|Orientation=1|Symbol=Thin Cross|IsActive=T|SuppressAll=T
|RECORD=22|IndexInSheet=165|OwnerPartId=-1|Location.X=1160|Location.Y=228|Color=255|Orientation=1|Symbol=Thin Cross|IsActive=T|SuppressAll=T
|RECORD=22|IndexInSheet=166|OwnerPartId=-1|Location.X=1160|Location.Y=218|Color=255|Orientation=1|Symbol=Thin Cross|IsActive=T|SuppressAll=T
|RECORD=22|IndexInSheet=167|OwnerPartId=-1|Location.X=1280|Location.Y=218|Color=255|Orientation=1|Symbol=Thin Cross|IsActive=T|SuppressAll=T
|RECORD=22|IndexInSheet=168|OwnerPartId=-1|Location.X=1280|Location.Y=228|Color=255|Orientation=1|Symbol=Thin Cross|IsActive=T|SuppressAll=T
|RECORD=22|IndexInSheet=169|OwnerPartId=-1|Location.X=1280|Location.Y=238|Color=255|Orientation=1|Symbol=Thin Cross|IsActive=T|SuppressAll=T
|RECORD=22|IndexInSheet=170|OwnerPartId=-1|Location.X=1280|Location.Y=248|Color=255|Orientation=1|Symbol=Thin Cross|IsActive=T|SuppressAll=T
|RECORD=22|IndexInSheet=171|OwnerPartId=-1|Location.X=1280|Location.Y=198|Color=255|Orientation=1|Symbol=Thin Cross|IsActive=T|SuppressAll=T
|RECORD=22|IndexInSheet=172|OwnerPartId=-1|Location.X=1280|Location.Y=188|Color=255|Orientation=1|Symbol=Thin Cross|IsActive=T|SuppressAll=T
|RECORD=22|IndexInSheet=173|OwnerPartId=-1|Location.X=1280|Location.Y=178|Color=255|Orientation=1|Symbol=Thin Cross|IsActive=T|SuppressAll=T
|RECORD=22|IndexInSheet=174|OwnerPartId=-1|Location.X=1280|Location.Y=168|Color=255|Orientation=1|Symbol=Thin Cross|IsActive=T|SuppressAll=T
|RECORD=22|IndexInSheet=175|OwnerPartId=-1|Location.X=1160|Location.Y=198|Color=255|Orientation=1|Symbol=Thin Cross|IsActive=T|SuppressAll=T
|RECORD=22|IndexInSheet=176|OwnerPartId=-1|Location.X=1160|Location.Y=188|Color=255|Orientation=1|Symbol=Thin Cross|IsActive=T|SuppressAll=T
|RECORD=22|IndexInSheet=177|OwnerPartId=-1|Location.X=1160|Location.Y=178|Color=255|Orientation=1|Symbol=Thin Cross|IsActive=T|SuppressAll=T
|RECORD=22|IndexInSheet=178|OwnerPartId=-1|Location.X=1160|Location.Y=168|Color=255|Orientation=1|Symbol=Thin Cross|IsActive=T|SuppressAll=T
|RECORD=22|IndexInSheet=179|OwnerPartId=-1|Location.X=1160|Location.Y=148|Color=255|Orientation=1|Symbol=Thin Cross|IsActive=T|SuppressAll=T
|RECORD=22|IndexInSheet=180|OwnerPartId=-1|Location.X=1160|Location.Y=138|Color=255|Orientation=1|Symbol=Thin Cross|IsActive=T|SuppressAll=T
|RECORD=22|IndexInSheet=181|OwnerPartId=-1|Location.X=1160|Location.Y=118|Color=255|Orientation=1|Symbol=Thin Cross|IsActive=T|SuppressAll=T
|RECORD=22|IndexInSheet=182|OwnerPartId=-1|Location.X=1160|Location.Y=128|Color=255|Orientation=1|Symbol=Thin Cross|IsActive=T|SuppressAll=T
|RECORD=22|IndexInSheet=183|OwnerPartId=-1|Location.X=1160|Location.Y=98|Color=255|Orientation=1|Symbol=Thin Cross|IsActive=T|SuppressAll=T
|RECORD=22|IndexInSheet=184|OwnerPartId=-1|Location.X=1160|Location.Y=88|Color=255|Orientation=1|Symbol=Thin Cross|IsActive=T|SuppressAll=T
|RECORD=22|IndexInSheet=185|OwnerPartId=-1|Location.X=1280|Location.Y=88|Color=255|Orientation=1|Symbol=Thin Cross|IsActive=T|SuppressAll=T
|RECORD=22|IndexInSheet=186|OwnerPartId=-1|Location.X=1280|Location.Y=98|Color=255|Orientation=1|Symbol=Thin Cross|IsActive=T|SuppressAll=T
|RECORD=22|IndexInSheet=187|OwnerPartId=-1|Location.X=1280|Location.Y=118|Color=255|Orientation=1|Symbol=Thin Cross|IsActive=T|SuppressAll=T
|RECORD=22|IndexInSheet=188|OwnerPartId=-1|Location.X=1280|Location.Y=128|Color=255|Orientation=1|Symbol=Thin Cross|IsActive=T|SuppressAll=T
|RECORD=22|IndexInSheet=189|OwnerPartId=-1|Location.X=1280|Location.Y=138|Color=255|Orientation=1|Symbol=Thin Cross|IsActive=T|SuppressAll=T
|RECORD=22|IndexInSheet=190|OwnerPartId=-1|Location.X=1280|Location.Y=148|Color=255|Orientation=1|Symbol=Thin Cross|IsActive=T|SuppressAll=T
|RECORD=22|IndexInSheet=191|OwnerPartId=-1|Location.X=460|Location.Y=488|Color=255|Orientation=1|Symbol=Thin Cross|IsActive=T|SuppressAll=T
|RECORD=22|IndexInSheet=192|OwnerPartId=-1|Location.X=580|Location.Y=488|Color=255|Orientation=1|Symbol=Thin Cross|IsActive=T|SuppressAll=T
|RECORD=22|IndexInSheet=193|OwnerPartId=-1|Location.X=580|Location.Y=478|Color=255|Orientation=1|Symbol=Thin Cross|IsActive=T|SuppressAll=T
|RECORD=22|IndexInSheet=194|OwnerPartId=-1|Location.X=580|Location.Y=468|Color=255|Orientation=1|Symbol=Thin Cross|IsActive=T|SuppressAll=T
|RECORD=22|IndexInSheet=195|OwnerPartId=-1|Location.X=460|Location.Y=438|Color=255|Orientation=1|Symbol=Thin Cross|IsActive=T|SuppressAll=T
|RECORD=22|IndexInSheet=196|OwnerPartId=-1|Location.X=460|Location.Y=428|Color=255|Orientation=1|Symbol=Thin Cross|IsActive=T|SuppressAll=T
|RECORD=22|IndexInSheet=197|OwnerPartId=-1|Location.X=460|Location.Y=418|Color=255|Orientation=1|Symbol=Thin Cross|IsActive=T|SuppressAll=T
|RECORD=22|IndexInSheet=198|OwnerPartId=-1|Location.X=460|Location.Y=378|Color=255|Orientation=1|Symbol=Thin Cross|IsActive=T|SuppressAll=T
|RECORD=22|IndexInSheet=199|OwnerPartId=-1|Location.X=460|Location.Y=368|Color=255|Orientation=1|Symbol=Thin Cross|IsActive=T|SuppressAll=T
|RECORD=22|IndexInSheet=200|OwnerPartId=-1|Location.X=460|Location.Y=238|Color=255|Orientation=1|Symbol=Thin Cross|IsActive=T|SuppressAll=T
|RECORD=22|IndexInSheet=201|OwnerPartId=-1|Location.X=460|Location.Y=228|Color=255|Orientation=1|Symbol=Thin Cross|IsActive=T|SuppressAll=T
|RECORD=22|IndexInSheet=202|OwnerPartId=-1|Location.X=460|Location.Y=218|Color=255|Orientation=1|Symbol=Thin Cross|IsActive=T|SuppressAll=T
|RECORD=22|IndexInSheet=203|OwnerPartId=-1|Location.X=580|Location.Y=248|Color=255|Orientation=1|Symbol=Thin Cross|IsActive=T|SuppressAll=T
|RECORD=22|IndexInSheet=204|OwnerPartId=-1|Location.X=580|Location.Y=238|Color=255|Orientation=1|Symbol=Thin Cross|IsActive=T|SuppressAll=T
|RECORD=22|IndexInSheet=205|OwnerPartId=-1|Location.X=580|Location.Y=228|Color=255|Orientation=1|Symbol=Thin Cross|IsActive=T|SuppressAll=T
|RECORD=22|IndexInSheet=206|OwnerPartId=-1|Location.X=580|Location.Y=218|Color=255|Orientation=1|Symbol=Thin Cross|IsActive=T|SuppressAll=T
|RECORD=22|IndexInSheet=207|OwnerPartId=-1|Location.X=460|Location.Y=198|Color=255|Orientation=1|Symbol=Thin Cross|IsActive=T|SuppressAll=T
|RECORD=22|IndexInSheet=208|OwnerPartId=-1|Location.X=460|Location.Y=188|Color=255|Orientation=1|Symbol=Thin Cross|IsActive=T|SuppressAll=T
|RECORD=22|IndexInSheet=209|OwnerPartId=-1|Location.X=460|Location.Y=178|Color=255|Orientation=1|Symbol=Thin Cross|IsActive=T|SuppressAll=T
|RECORD=22|IndexInSheet=210|OwnerPartId=-1|Location.X=460|Location.Y=168|Color=255|Orientation=1|Symbol=Thin Cross|IsActive=T|SuppressAll=T
|RECORD=22|IndexInSheet=211|OwnerPartId=-1|Location.X=580|Location.Y=198|Color=255|Orientation=1|Symbol=Thin Cross|IsActive=T|SuppressAll=T
|RECORD=22|IndexInSheet=212|OwnerPartId=-1|Location.X=580|Location.Y=188|Color=255|Orientation=1|Symbol=Thin Cross|IsActive=T|SuppressAll=T
|RECORD=22|IndexInSheet=213|OwnerPartId=-1|Location.X=580|Location.Y=178|Color=255|Orientation=1|Symbol=Thin Cross|IsActive=T|SuppressAll=T
|RECORD=22|IndexInSheet=214|OwnerPartId=-1|Location.X=580|Location.Y=168|Color=255|Orientation=1|Symbol=Thin Cross|IsActive=T|SuppressAll=T
|RECORD=22|IndexInSheet=215|OwnerPartId=-1|Location.X=580|Location.Y=148|Color=255|Orientation=1|Symbol=Thin Cross|IsActive=T|SuppressAll=T
|RECORD=22|IndexInSheet=216|OwnerPartId=-1|Location.X=580|Location.Y=138|Color=255|Orientation=1|Symbol=Thin Cross|IsActive=T|SuppressAll=T
|RECORD=22|IndexInSheet=217|OwnerPartId=-1|Location.X=460|Location.Y=148|Color=255|Orientation=1|Symbol=Thin Cross|IsActive=T|SuppressAll=T
|RECORD=22|IndexInSheet=218|OwnerPartId=-1|Location.X=460|Location.Y=148|Color=255|Orientation=1|Symbol=Thin Cross|IsActive=T|SuppressAll=T
|RECORD=22|IndexInSheet=219|OwnerPartId=-1|Location.X=460|Location.Y=138|Color=255|Orientation=1|Symbol=Thin Cross|IsActive=T|SuppressAll=T
|RECORD=22|IndexInSheet=220|OwnerPartId=-1|Location.X=460|Location.Y=98|Color=255|Orientation=1|Symbol=Thin Cross|IsActive=T|SuppressAll=T
|RECORD=22|IndexInSheet=221|OwnerPartId=-1|Location.X=460|Location.Y=88|Color=255|Orientation=1|Symbol=Thin Cross|IsActive=T|SuppressAll=T
|RECORD=22|IndexInSheet=222|OwnerPartId=-1|Location.X=580|Location.Y=88|Color=255|Orientation=1|Symbol=Thin Cross|IsActive=T|SuppressAll=T
|RECORD=22|IndexInSheet=223|OwnerPartId=-1|Location.X=580|Location.Y=98|Color=255|Orientation=1|Symbol=Thin Cross|IsActive=T|SuppressAll=T
|RECORD=41|IndexInSheet=224|OwnerPartId=-1|Color=8388608|FontID=1|IsHidden=T|Name=ConfigurationParameters|ReadOnlyState=1
|RECORD=41|IndexInSheet=225|OwnerPartId=-1|Color=8388608|FontID=1|IsHidden=T|Name=ConfiguratorName|ReadOnlyState=1
|RECORD=41|IndexInSheet=226|OwnerPartId=-1|Color=8388608|FontID=1|IsHidden=T|Name=VersionControl_RevNumber|ReadOnlyState=1
|RECORD=41|IndexInSheet=227|OwnerPartId=-1|Color=8388608|FontID=1|IsHidden=T|Name=IsUserConfigurable|ReadOnlyState=1
|RECORD=41|IndexInSheet=228|OwnerPartId=-1|Color=8388608|FontID=1|IsHidden=T|Name=VersionControl_ProjFolderRevNumber|ReadOnlyState=1
|RECORD=41|IndexInSheet=229|OwnerPartId=-1|Color=8388608|FontID=1|IsHidden=T|Name=SPICEModelCache|ReadOnlyState=1
|RECORD=22|IndexInSheet=230|OwnerPartId=-1|Location.X=1290|Location.Y=968|Color=255|Orientation=1|Symbol=Thin Cross|IsActive=T|SuppressAll=T
|RECORD=22|IndexInSheet=231|OwnerPartId=-1|Location.X=1170|Location.Y=788|Color=255|Orientation=1|Symbol=Thin Cross|IsActive=T|SuppressAll=T
|RECORD=22|IndexInSheet=232|OwnerPartId=-1|Location.X=1170|Location.Y=768|Color=255|Orientation=1|Symbol=Thin Cross|IsActive=T|SuppressAll=T
|RECORD=22|IndexInSheet=233|OwnerPartId=-1|Location.X=1170|Location.Y=738|Color=255|Orientation=1|Symbol=Thin Cross|IsActive=T|SuppressAll=T
|RECORD=17|IndexInSheet=234|OwnerPartId=-1|ShowNetName=T|Location.X=1061|Location.Y=638|Orientation=2|Color=255|FontID=1|Text=UART1_TXD|IsCrossSheetConnector=T
|RECORD=17|IndexInSheet=235|OwnerPartId=-1|ShowNetName=T|Location.X=1060|Location.Y=608|Orientation=2|Color=255|FontID=1|Text=UART1_RXD|IsCrossSheetConnector=T
|RECORD=17|IndexInSheet=236|OwnerPartId=-1|ShowNetName=T|Location.X=690|Location.Y=448|Color=255|FontID=1|Text=IO_LED1|IsCrossSheetConnector=T
|RECORD=17|IndexInSheet=237|OwnerPartId=-1|ShowNetName=T|Location.X=690|Location.Y=438|Color=255|FontID=1|Text=IO_LED2|IsCrossSheetConnector=T
|RECORD=17|IndexInSheet=238|OwnerPartId=-1|ShowNetName=T|Location.X=690|Location.Y=428|Color=255|FontID=1|Text=IO_LED3|IsCrossSheetConnector=T
|RECORD=17|IndexInSheet=239|OwnerPartId=-1|ShowNetName=T|Location.X=691|Location.Y=418|Color=255|FontID=1|Text=IO_LED4|IsCrossSheetConnector=T
|RECORD=17|IndexInSheet=240|OwnerPartId=-1|ShowNetName=T|Location.X=690|Location.Y=498|Color=255|FontID=1|Text=GPS2_RX_FPGA|IsCrossSheetConnector=T
|RECORD=17|IndexInSheet=241|OwnerPartId=-1|ShowNetName=T|Location.X=318|Location.Y=498|Orientation=2|Color=255|FontID=1|Text=GPS2_TX_FPGA|IsCrossSheetConnector=T
|RECORD=17|IndexInSheet=242|OwnerPartId=-1|ShowNetName=T|Location.X=319|Location.Y=468|Orientation=2|Color=255|FontID=1|Text=GPS2_TP2|IsCrossSheetConnector=T
|RECORD=17|IndexInSheet=243|OwnerPartId=-1|ShowNetName=T|Location.X=319|Location.Y=478|Orientation=2|Color=255|FontID=1|Text=GPS2_TP1|IsCrossSheetConnector=T
|RECORD=17|IndexInSheet=244|OwnerPartId=-1|ShowNetName=T|Location.X=319|Location.Y=448|Orientation=2|Color=255|FontID=1|Text=GPS2_RST|IsCrossSheetConnector=T
|RECORD=22|IndexInSheet=245|OwnerPartId=-1|Location.X=460|Location.Y=888|Color=255|Orientation=1|Symbol=Thin Cross|IsActive=T|SuppressAll=T
|RECORD=22|IndexInSheet=246|OwnerPartId=-1|Location.X=460|Location.Y=878|Color=255|Orientation=1|Symbol=Thin Cross|IsActive=T|SuppressAll=T
|RECORD=22|IndexInSheet=247|OwnerPartId=-1|Location.X=460|Location.Y=868|Color=255|Orientation=1|Symbol=Thin Cross|IsActive=T|SuppressAll=T
|RECORD=22|IndexInSheet=248|OwnerPartId=-1|Location.X=460|Location.Y=858|Color=255|Orientation=1|Symbol=Thin Cross|IsActive=T|SuppressAll=T
|RECORD=22|IndexInSheet=249|OwnerPartId=-1|Location.X=460|Location.Y=818|Color=255|Orientation=1|Symbol=Thin Cross|IsActive=T|SuppressAll=T
|RECORD=22|IndexInSheet=250|OwnerPartId=-1|Location.X=460|Location.Y=778|Color=255|Orientation=1|Symbol=Thin Cross|IsActive=T|SuppressAll=T
|RECORD=22|IndexInSheet=251|OwnerPartId=-1|Location.X=460|Location.Y=768|Color=255|Orientation=1|Symbol=Thin Cross|IsActive=T|SuppressAll=T
|RECORD=22|IndexInSheet=252|OwnerPartId=-1|Location.X=1170|Location.Y=838|Color=255|Orientation=1|Symbol=Thin Cross|IsActive=T|SuppressAll=T
|RECORD=17|IndexInSheet=253|OwnerPartId=-1|ShowNetName=T|Location.X=320|Location.Y=348|Orientation=2|Color=255|FontID=1|Text=ANT1_IO_OUT|IsCrossSheetConnector=T
|RECORD=17|IndexInSheet=254|OwnerPartId=-1|ShowNetName=T|Location.X=320|Location.Y=338|Orientation=2|Color=255|FontID=1|Text=ANT1_IO_IN|IsCrossSheetConnector=T
|RECORD=17|IndexInSheet=255|OwnerPartId=-1|ShowNetName=T|Location.X=320|Location.Y=328|Orientation=2|Color=255|FontID=1|Text=ANT2_IO_OUT|IsCrossSheetConnector=T
|RECORD=17|IndexInSheet=256|OwnerPartId=-1|ShowNetName=T|Location.X=320|Location.Y=318|Orientation=2|Color=255|FontID=1|Text=ANT2_IO_IN|IsCrossSheetConnector=T
|RECORD=17|IndexInSheet=257|OwnerPartId=-1|ShowNetName=T|Location.X=320|Location.Y=298|Orientation=2|Color=255|FontID=1|Text=ANT3_IO_OUT|IsCrossSheetConnector=T
|RECORD=17|IndexInSheet=258|OwnerPartId=-1|ShowNetName=T|Location.X=320|Location.Y=288|Orientation=2|Color=255|FontID=1|Text=ANT3_IO_IN|IsCrossSheetConnector=T
|RECORD=17|IndexInSheet=259|OwnerPartId=-1|ShowNetName=T|Location.X=320|Location.Y=278|Orientation=2|Color=255|FontID=1|Text=ANT4_IO_OUT|IsCrossSheetConnector=T
|RECORD=17|IndexInSheet=260|OwnerPartId=-1|ShowNetName=T|Location.X=320|Location.Y=268|Orientation=2|Color=255|FontID=1|Text=ANT4_IO_IN|IsCrossSheetConnector=T
|RECORD=17|IndexInSheet=261|OwnerPartId=-1|ShowNetName=T|Location.X=691|Location.Y=348|Color=255|FontID=1|Text=EXT_GPIO_7|IsCrossSheetConnector=T
|RECORD=17|IndexInSheet=262|OwnerPartId=-1|ShowNetName=T|Location.X=691|Location.Y=338|Color=255|FontID=1|Text=EXT_GPIO_8|IsCrossSheetConnector=T
|RECORD=17|IndexInSheet=263|OwnerPartId=-1|ShowNetName=T|Location.X=691|Location.Y=328|Color=255|FontID=1|Text=EXT_GPIO_9|IsCrossSheetConnector=T
|RECORD=17|IndexInSheet=264|OwnerPartId=-1|ShowNetName=T|Location.X=691|Location.Y=318|Color=255|FontID=1|Text=EXT_GPIO_10|IsCrossSheetConnector=T
|RECORD=41|IndexInSheet=265|OwnerPartId=-1|Color=8388608|FontID=1|IsHidden=T|Text=*|Name=CurrentTime|ReadOnlyState=1
|RECORD=41|IndexInSheet=266|OwnerPartId=-1|Color=8388608|FontID=1|IsHidden=T|Text=*|Name=CurrentDate|ReadOnlyState=1
|RECORD=41|IndexInSheet=267|OwnerPartId=-1|Color=8388608|FontID=1|IsHidden=T|Text=*|Name=Time|ReadOnlyState=1
|RECORD=41|IndexInSheet=268|OwnerPartId=-1|Color=8388608|FontID=1|IsHidden=T|Text=*|Name=Date|ReadOnlyState=1
|RECORD=41|IndexInSheet=269|OwnerPartId=-1|Color=8388608|FontID=1|IsHidden=T|Text=*|Name=DocumentFullPathAndName|ReadOnlyState=1
|RECORD=41|IndexInSheet=270|OwnerPartId=-1|Color=8388608|FontID=1|IsHidden=T|Text=*|Name=DocumentName|ReadOnlyState=1
|RECORD=41|IndexInSheet=271|OwnerPartId=-1|Color=8388608|FontID=1|IsHidden=T|Text=*|Name=ModifiedDate|ReadOnlyState=1
|RECORD=41|IndexInSheet=272|OwnerPartId=-1|Color=8388608|FontID=1|IsHidden=T|Text=*|Name=ApprovedBy|ReadOnlyState=1
|RECORD=41|IndexInSheet=273|OwnerPartId=-1|Color=8388608|FontID=1|IsHidden=T|Text=*|Name=CheckedBy|ReadOnlyState=1
|RECORD=41|IndexInSheet=274|OwnerPartId=-1|Color=8388608|FontID=1|IsHidden=T|Text=*|Name=Author|ReadOnlyState=1
|RECORD=41|IndexInSheet=275|OwnerPartId=-1|Color=8388608|FontID=1|IsHidden=T|Text=*|Name=CompanyName|ReadOnlyState=1
|RECORD=41|IndexInSheet=276|OwnerPartId=-1|Color=8388608|FontID=1|IsHidden=T|Text=*|Name=DrawnBy|ReadOnlyState=1
|RECORD=41|IndexInSheet=277|OwnerPartId=-1|Color=8388608|FontID=1|IsHidden=T|Text=*|Name=Engineer|ReadOnlyState=1
|RECORD=41|IndexInSheet=278|OwnerPartId=-1|Color=8388608|FontID=1|IsHidden=T|Text=*|Name=Organization|ReadOnlyState=1
|RECORD=41|IndexInSheet=279|OwnerPartId=-1|Color=8388608|FontID=1|IsHidden=T|Text=*|Name=Address1|ReadOnlyState=1
|RECORD=41|IndexInSheet=280|OwnerPartId=-1|Color=8388608|FontID=1|IsHidden=T|Text=*|Name=Address2|ReadOnlyState=1
|RECORD=41|IndexInSheet=281|OwnerPartId=-1|Color=8388608|FontID=1|IsHidden=T|Text=*|Name=Address3|ReadOnlyState=1
|RECORD=41|IndexInSheet=282|OwnerPartId=-1|Color=8388608|FontID=1|IsHidden=T|Text=*|Name=Address4|ReadOnlyState=1
|RECORD=41|IndexInSheet=283|OwnerPartId=-1|Color=8388608|FontID=1|IsHidden=T|Text=*|Name=Title|ReadOnlyState=1
|RECORD=41|IndexInSheet=284|OwnerPartId=-1|Color=8388608|FontID=1|IsHidden=T|Text=*|Name=DocumentNumber|ReadOnlyState=1
|RECORD=41|IndexInSheet=285|OwnerPartId=-1|Color=8388608|FontID=1|IsHidden=T|Text=*|Name=Revision|ReadOnlyState=1
|RECORD=41|IndexInSheet=286|OwnerPartId=-1|Color=8388608|FontID=1|IsHidden=T|Text=*|Name=SheetNumber|ReadOnlyState=1
|RECORD=41|IndexInSheet=287|OwnerPartId=-1|Color=8388608|FontID=1|IsHidden=T|Text=*|Name=SheetTotal|ReadOnlyState=1
|RECORD=41|IndexInSheet=288|OwnerPartId=-1|Color=8388608|FontID=1|IsHidden=T|Text=*|Name=Rule|ReadOnlyState=1
|RECORD=41|IndexInSheet=289|OwnerPartId=-1|Color=8388608|FontID=1|IsHidden=T|Text=*|Name=ImagePath|ReadOnlyState=1
|RECORD=41|IndexInSheet=290|OwnerPartId=-1|Color=8388608|FontID=1|IsHidden=T|Text=*|Name=ProjectName|ReadOnlyState=1
|RECORD=41|IndexInSheet=291|OwnerPartId=-1|Color=8388608|FontID=1|IsHidden=T|Text=*|Name=Application_BuildNumber|ReadOnlyState=1
|RECORD=22|IndexInSheet=292|OwnerPartId=-1|Location.X=580|Location.Y=768|Color=255|Orientation=1|Symbol=Thin Cross|IsActive=T|SuppressAll=T
|RECORD=22|IndexInSheet=293|OwnerPartId=-1|Location.X=580|Location.Y=758|Color=255|Orientation=1|Symbol=Thin Cross|IsActive=T|SuppressAll=T
|RECORD=22|IndexInSheet=294|OwnerPartId=-1|Location.X=580|Location.Y=728|Color=255|Orientation=1|Symbol=Thin Cross|IsActive=T|SuppressAll=T
|RECORD=22|IndexInSheet=295|OwnerPartId=-1|Location.X=580|Location.Y=718|Color=255|Orientation=1|Symbol=Thin Cross|IsActive=T|SuppressAll=T
|RECORD=22|IndexInSheet=296|OwnerPartId=-1|Location.X=580|Location.Y=688|Color=255|Orientation=1|Symbol=Thin Cross|IsActive=T|SuppressAll=T
|RECORD=22|IndexInSheet=297|OwnerPartId=-1|Location.X=580|Location.Y=678|Color=255|Orientation=1|Symbol=Thin Cross|IsActive=T|SuppressAll=T
|RECORD=22|IndexInSheet=298|OwnerPartId=-1|Location.X=1290|Location.Y=678|Color=255|Orientation=1|Symbol=Thin Cross|IsActive=T|SuppressAll=T
|RECORD=22|IndexInSheet=299|OwnerPartId=-1|Location.X=1290|Location.Y=828|Color=255|Orientation=1|Symbol=Thin Cross|IsActive=T|SuppressAll=T
|RECORD=22|IndexInSheet=300|OwnerPartId=-1|Location.X=460|Location.Y=248|Color=255|Orientation=1|Symbol=Thin Cross|IsActive=T|SuppressAll=T
|RECORD=17|IndexInSheet=301|OwnerPartId=-1|ShowNetName=T|Location.X=691|Location.Y=298|Color=255|FontID=1|Text=EXT_GPIO_1|IsCrossSheetConnector=T
|RECORD=17|IndexInSheet=302|OwnerPartId=-1|ShowNetName=T|Location.X=691|Location.Y=288|Color=255|FontID=1|Text=EXT_GPIO_2|IsCrossSheetConnector=T
|RECORD=17|IndexInSheet=303|OwnerPartId=-1|ShowNetName=T|Location.X=691|Location.Y=278|Color=255|FontID=1|Text=EXT_GPIO_3|IsCrossSheetConnector=T
|RECORD=17|IndexInSheet=304|OwnerPartId=-1|ShowNetName=T|Location.X=691|Location.Y=268|Color=255|FontID=1|Text=EXT_GPIO_4|IsCrossSheetConnector=T
|RECORD=17|IndexInSheet=305|OwnerPartId=-1|ShowNetName=T|Location.X=1059|Location.Y=918|Orientation=2|Color=255|FontID=1|Text=ANT1_OUT|IsCrossSheetConnector=T
|RECORD=17|IndexInSheet=306|OwnerPartId=-1|ShowNetName=T|Location.X=1059|Location.Y=888|Orientation=2|Color=255|FontID=1|Text=ANT1_IN|IsCrossSheetConnector=T
|RECORD=17|IndexInSheet=307|OwnerPartId=-1|ShowNetName=T|Location.X=1059|Location.Y=908|Orientation=2|Color=255|FontID=1|Text=ANT2_OUT|IsCrossSheetConnector=T
|RECORD=17|IndexInSheet=308|OwnerPartId=-1|ShowNetName=T|Location.X=1059|Location.Y=878|Orientation=2|Color=255|FontID=1|Text=ANT2_IN|IsCrossSheetConnector=T
|RECORD=17|IndexInSheet=309|OwnerPartId=-1|ShowNetName=T|Location.X=1059|Location.Y=868|Orientation=2|Color=255|FontID=1|Text=ANT3_OUT|IsCrossSheetConnector=T
|RECORD=17|IndexInSheet=310|OwnerPartId=-1|ShowNetName=T|Location.X=1352|Location.Y=918|Color=255|FontID=1|Text=ANT3_IN|IsCrossSheetConnector=T
|RECORD=17|IndexInSheet=311|OwnerPartId=-1|ShowNetName=T|Location.X=1059|Location.Y=858|Orientation=2|Color=255|FontID=1|Text=ANT4_OUT|IsCrossSheetConnector=T
|RECORD=17|IndexInSheet=312|OwnerPartId=-1|ShowNetName=T|Location.X=1352|Location.Y=908|Color=255|FontID=1|Text=ANT4_IN|IsCrossSheetConnector=T
|RECORD=17|IndexInSheet=313|OwnerPartId=-1|ShowNetName=T|Location.X=691|Location.Y=778|Color=255|FontID=1|Text=EXT_EEPROM_WP|IsCrossSheetConnector=T
|RECORD=1|LibReference=Single FPGA Conn|PartCount=2|DisplayModeCount=1|IndexInSheet=314|OwnerPartId=-1|Location.X=460|Location.Y=578|CurrentPartId=1|LibraryPath=*|SourceLibraryName=FPGA_CONN.SchLib|TargetFileName=*|AreaColor=11599871|Color=128|PartIDLocked=T|PinsMoveable=T|DesignItemId=Single FPGA Conn|AllPinCount=84
|RECORD=41|OwnerIndex=348|OwnerPartId=-1|Location.X=455|Location.Y=998|Color=8388608|FontID=1|IsHidden=T|Text=Digi-Key|Name=Supplier 1|ReadOnlyState=3
|RECORD=41|OwnerIndex=348|IndexInSheet=1|OwnerPartId=-1|Location.X=490|Location.Y=998|Color=8388608|FontID=1|IsHidden=T|Text=255-3246-1-ND|Name=Supplier Part Number 1|ReadOnlyState=3
|RECORD=41|OwnerIndex=348|IndexInSheet=2|OwnerPartId=-1|Location.X=490|Location.Y=548|Color=8388608|FontID=1|Text=AXK680347YG|Name=Part Number
|RECORD=14|OwnerIndex=348|IsNotAccesible=T|IndexInSheet=3|OwnerPartId=1|Location.X=490|Location.Y=568|Corner.X=550|Corner.Y=998|Color=128|AreaColor=11599871|IsSolid=T
|RECORD=2|OwnerIndex=348|OwnerPartId=1|FormalType=1|PinConglomerate=26|PinLength=30|Location.X=490|Location.Y=988|Name=1|Designator=1|PinPropagationDelay=0.000000E+000
|RECORD=2|OwnerIndex=348|OwnerPartId=1|FormalType=1|PinConglomerate=24|PinLength=30|Location.X=550|Location.Y=988|Name=2|Designator=2|PinPropagationDelay=0.000000E+000
|RECORD=2|OwnerIndex=348|OwnerPartId=1|FormalType=1|PinConglomerate=26|PinLength=30|Location.X=490|Location.Y=978|Name=3|Designator=3|PinPropagationDelay=0.000000E+000
|RECORD=2|OwnerIndex=348|OwnerPartId=1|FormalType=1|PinConglomerate=24|PinLength=30|Location.X=550|Location.Y=978|Name=4|Designator=4|PinPropagationDelay=0.000000E+000
|RECORD=2|OwnerIndex=348|OwnerPartId=1|FormalType=1|PinConglomerate=26|PinLength=30|Location.X=490|Location.Y=968|Name=5|Designator=5|PinPropagationDelay=0.000000E+000
|RECORD=2|OwnerIndex=348|OwnerPartId=1|FormalType=1|PinConglomerate=24|PinLength=30|Location.X=550|Location.Y=968|Name=6|Designator=6|PinPropagationDelay=0.000000E+000
|RECORD=2|OwnerIndex=348|OwnerPartId=1|FormalType=1|PinConglomerate=26|PinLength=30|Location.X=490|Location.Y=958|Name=7|Designator=7|PinPropagationDelay=0.000000E+000
|RECORD=2|OwnerIndex=348|OwnerPartId=1|FormalType=1|PinConglomerate=24|PinLength=30|Location.X=550|Location.Y=958|Name=8|Designator=8|PinPropagationDelay=0.000000E+000
|RECORD=2|OwnerIndex=348|OwnerPartId=1|FormalType=1|PinConglomerate=26|PinLength=30|Location.X=490|Location.Y=948|Name=9|Designator=9|PinPropagationDelay=0.000000E+000
|RECORD=2|OwnerIndex=348|OwnerPartId=1|FormalType=1|PinConglomerate=24|PinLength=30|Location.X=550|Location.Y=948|Name=10|Designator=10|PinPropagationDelay=0.000000E+000
|RECORD=2|OwnerIndex=348|OwnerPartId=1|FormalType=1|PinConglomerate=26|PinLength=30|Location.X=490|Location.Y=938|Name=11|Designator=11|PinPropagationDelay=0.000000E+000
|RECORD=2|OwnerIndex=348|OwnerPartId=1|FormalType=1|PinConglomerate=24|PinLength=30|Location.X=550|Location.Y=938|Name=12|Designator=12|PinPropagationDelay=0.000000E+000
|RECORD=2|OwnerIndex=348|OwnerPartId=1|FormalType=1|PinConglomerate=26|PinLength=30|Location.X=490|Location.Y=928|Name=13|Designator=13|PinPropagationDelay=0.000000E+000
|RECORD=2|OwnerIndex=348|OwnerPartId=1|FormalType=1|PinConglomerate=24|PinLength=30|Location.X=550|Location.Y=928|Name=14|Designator=14|PinPropagationDelay=0.000000E+000
|RECORD=2|OwnerIndex=348|OwnerPartId=1|FormalType=1|PinConglomerate=26|PinLength=30|Location.X=490|Location.Y=918|Name=15|Designator=15|PinPropagationDelay=0.000000E+000
|RECORD=2|OwnerIndex=348|OwnerPartId=1|FormalType=1|PinConglomerate=24|PinLength=30|Location.X=550|Location.Y=918|Name=16|Designator=16|PinPropagationDelay=0.000000E+000
|RECORD=2|OwnerIndex=348|OwnerPartId=1|FormalType=1|PinConglomerate=26|PinLength=30|Location.X=490|Location.Y=908|Name=17|Designator=17|PinPropagationDelay=0.000000E+000
|RECORD=2|OwnerIndex=348|OwnerPartId=1|FormalType=1|PinConglomerate=24|PinLength=30|Location.X=550|Location.Y=908|Name=18|Designator=18|PinPropagationDelay=0.000000E+000
|RECORD=2|OwnerIndex=348|OwnerPartId=1|FormalType=1|PinConglomerate=26|PinLength=30|Location.X=490|Location.Y=898|Name=19|Designator=19|PinPropagationDelay=0.000000E+000
|RECORD=2|OwnerIndex=348|OwnerPartId=1|FormalType=1|PinConglomerate=24|PinLength=30|Location.X=550|Location.Y=898|Name=20|Designator=20|PinPropagationDelay=0.000000E+000
|RECORD=2|OwnerIndex=348|OwnerPartId=1|FormalType=1|PinConglomerate=26|PinLength=30|Location.X=490|Location.Y=888|Name=21|Designator=21|PinPropagationDelay=0.000000E+000
|RECORD=2|OwnerIndex=348|OwnerPartId=1|FormalType=1|PinConglomerate=24|PinLength=30|Location.X=550|Location.Y=888|Name=22|Designator=22|PinPropagationDelay=0.000000E+000
|RECORD=2|OwnerIndex=348|OwnerPartId=1|FormalType=1|PinConglomerate=26|PinLength=30|Location.X=490|Location.Y=878|Name=23|Designator=23|PinPropagationDelay=0.000000E+000
|RECORD=2|OwnerIndex=348|OwnerPartId=1|FormalType=1|PinConglomerate=24|PinLength=30|Location.X=550|Location.Y=878|Name=24|Designator=24|PinPropagationDelay=0.000000E+000
|RECORD=2|OwnerIndex=348|OwnerPartId=1|FormalType=1|PinConglomerate=26|PinLength=30|Location.X=490|Location.Y=868|Name=25|Designator=25|PinPropagationDelay=0.000000E+000
|RECORD=2|OwnerIndex=348|OwnerPartId=1|FormalType=1|PinConglomerate=24|PinLength=30|Location.X=550|Location.Y=868|Name=26|Designator=26|PinPropagationDelay=0.000000E+000
|RECORD=2|OwnerIndex=348|OwnerPartId=1|FormalType=1|PinConglomerate=26|PinLength=30|Location.X=490|Location.Y=858|Name=27|Designator=27|PinPropagationDelay=0.000000E+000
|RECORD=2|OwnerIndex=348|OwnerPartId=1|FormalType=1|PinConglomerate=24|PinLength=30|Location.X=550|Location.Y=858|Name=28|Designator=28|PinPropagationDelay=0.000000E+000
|RECORD=2|OwnerIndex=348|OwnerPartId=1|FormalType=1|PinConglomerate=26|PinLength=30|Location.X=490|Location.Y=848|Name=29|Designator=29|PinPropagationDelay=0.000000E+000
|RECORD=2|OwnerIndex=348|OwnerPartId=1|FormalType=1|PinConglomerate=24|PinLength=30|Location.X=550|Location.Y=848|Name=30|Designator=30|PinPropagationDelay=0.000000E+000
|RECORD=2|OwnerIndex=348|OwnerPartId=1|FormalType=1|PinConglomerate=26|PinLength=30|Location.X=490|Location.Y=838|Name=31|Designator=31|PinPropagationDelay=0.000000E+000
|RECORD=2|OwnerIndex=348|OwnerPartId=1|FormalType=1|PinConglomerate=24|PinLength=30|Location.X=550|Location.Y=838|Name=32|Designator=32|PinPropagationDelay=0.000000E+000
|RECORD=2|OwnerIndex=348|OwnerPartId=1|FormalType=1|PinConglomerate=26|PinLength=30|Location.X=490|Location.Y=828|Name=33|Designator=33|PinPropagationDelay=0.000000E+000
|RECORD=2|OwnerIndex=348|OwnerPartId=1|FormalType=1|PinConglomerate=24|PinLength=30|Location.X=550|Location.Y=828|Name=34|Designator=34|PinPropagationDelay=0.000000E+000
|RECORD=2|OwnerIndex=348|OwnerPartId=1|FormalType=1|PinConglomerate=26|PinLength=30|Location.X=490|Location.Y=818|Name=35|Designator=35|PinPropagationDelay=0.000000E+000
|RECORD=2|OwnerIndex=348|OwnerPartId=1|FormalType=1|PinConglomerate=24|PinLength=30|Location.X=550|Location.Y=818|Name=36|Designator=36|PinPropagationDelay=0.000000E+000
|RECORD=2|OwnerIndex=348|OwnerPartId=1|FormalType=1|PinConglomerate=26|PinLength=30|Location.X=490|Location.Y=808|Name=37|Designator=37|PinPropagationDelay=0.000000E+000
|RECORD=2|OwnerIndex=348|OwnerPartId=1|FormalType=1|PinConglomerate=24|PinLength=30|Location.X=550|Location.Y=808|Name=38|Designator=38|PinPropagationDelay=0.000000E+000
|RECORD=2|OwnerIndex=348|OwnerPartId=1|FormalType=1|PinConglomerate=26|PinLength=30|Location.X=490|Location.Y=798|Name=39|Designator=39|PinPropagationDelay=0.000000E+000
|RECORD=2|OwnerIndex=348|OwnerPartId=1|FormalType=1|PinConglomerate=24|PinLength=30|Location.X=550|Location.Y=798|Name=40|Designator=40|PinPropagationDelay=0.000000E+000
|RECORD=2|OwnerIndex=348|OwnerPartId=1|FormalType=1|PinConglomerate=26|PinLength=30|Location.X=490|Location.Y=788|Name=41|Designator=41|PinPropagationDelay=0.000000E+000
|RECORD=2|OwnerIndex=348|OwnerPartId=1|FormalType=1|PinConglomerate=24|PinLength=30|Location.X=550|Location.Y=788|Name=42|Designator=42|PinPropagationDelay=0.000000E+000
|RECORD=2|OwnerIndex=348|OwnerPartId=1|FormalType=1|PinConglomerate=26|PinLength=30|Location.X=490|Location.Y=778|Name=43|Designator=43|PinPropagationDelay=0.000000E+000
|RECORD=2|OwnerIndex=348|OwnerPartId=1|FormalType=1|PinConglomerate=24|PinLength=30|Location.X=550|Location.Y=778|Name=44|Designator=44|PinPropagationDelay=0.000000E+000
|RECORD=2|OwnerIndex=348|OwnerPartId=1|FormalType=1|PinConglomerate=26|PinLength=30|Location.X=490|Location.Y=768|Name=45|Designator=45|PinPropagationDelay=0.000000E+000
|RECORD=2|OwnerIndex=348|OwnerPartId=1|FormalType=1|PinConglomerate=24|PinLength=30|Location.X=550|Location.Y=768|Name=46|Designator=46|PinPropagationDelay=0.000000E+000
|RECORD=2|OwnerIndex=348|OwnerPartId=1|FormalType=1|PinConglomerate=26|PinLength=30|Location.X=490|Location.Y=758|Name=47|Designator=47|PinPropagationDelay=0.000000E+000
|RECORD=2|OwnerIndex=348|OwnerPartId=1|FormalType=1|PinConglomerate=24|PinLength=30|Location.X=550|Location.Y=758|Name=48|Designator=48|PinPropagationDelay=0.000000E+000
|RECORD=2|OwnerIndex=348|OwnerPartId=1|FormalType=1|PinConglomerate=26|PinLength=30|Location.X=490|Location.Y=748|Name=49|Designator=49|PinPropagationDelay=0.000000E+000
|RECORD=2|OwnerIndex=348|OwnerPartId=1|FormalType=1|PinConglomerate=24|PinLength=30|Location.X=550|Location.Y=748|Name=50|Designator=50|PinPropagationDelay=0.000000E+000
|RECORD=2|OwnerIndex=348|OwnerPartId=1|FormalType=1|PinConglomerate=26|PinLength=30|Location.X=490|Location.Y=738|Name=51|Designator=51|PinPropagationDelay=0.000000E+000
|RECORD=2|OwnerIndex=348|OwnerPartId=1|FormalType=1|PinConglomerate=24|PinLength=30|Location.X=550|Location.Y=738|Name=52|Designator=52|PinPropagationDelay=0.000000E+000
|RECORD=2|OwnerIndex=348|OwnerPartId=1|FormalType=1|PinConglomerate=26|PinLength=30|Location.X=490|Location.Y=728|Name=53|Designator=53|PinPropagationDelay=0.000000E+000
|RECORD=2|OwnerIndex=348|OwnerPartId=1|FormalType=1|PinConglomerate=24|PinLength=30|Location.X=550|Location.Y=728|Name=54|Designator=54|PinPropagationDelay=0.000000E+000
|RECORD=2|OwnerIndex=348|OwnerPartId=1|FormalType=1|PinConglomerate=26|PinLength=30|Location.X=490|Location.Y=718|Name=55|Designator=55|PinPropagationDelay=0.000000E+000
|RECORD=2|OwnerIndex=348|OwnerPartId=1|FormalType=1|PinConglomerate=24|PinLength=30|Location.X=550|Location.Y=718|Name=56|Designator=56|PinPropagationDelay=0.000000E+000
|RECORD=2|OwnerIndex=348|OwnerPartId=1|FormalType=1|PinConglomerate=26|PinLength=30|Location.X=490|Location.Y=708|Name=57|Designator=57|PinPropagationDelay=0.000000E+000
|RECORD=2|OwnerIndex=348|OwnerPartId=1|FormalType=1|PinConglomerate=24|PinLength=30|Location.X=550|Location.Y=708|Name=58|Designator=58|PinPropagationDelay=0.000000E+000
|RECORD=2|OwnerIndex=348|OwnerPartId=1|FormalType=1|PinConglomerate=26|PinLength=30|Location.X=490|Location.Y=698|Name=59|Designator=59|PinPropagationDelay=0.000000E+000
|RECORD=2|OwnerIndex=348|OwnerPartId=1|FormalType=1|PinConglomerate=24|PinLength=30|Location.X=550|Location.Y=698|Name=60|Designator=60|PinPropagationDelay=0.000000E+000
|RECORD=2|OwnerIndex=348|OwnerPartId=1|FormalType=1|PinConglomerate=26|PinLength=30|Location.X=490|Location.Y=688|Name=61|Designator=61|PinPropagationDelay=0.000000E+000
|RECORD=2|OwnerIndex=348|OwnerPartId=1|FormalType=1|PinConglomerate=24|PinLength=30|Location.X=550|Location.Y=688|Name=62|Designator=62|PinPropagationDelay=0.000000E+000
|RECORD=2|OwnerIndex=348|OwnerPartId=1|FormalType=1|PinConglomerate=26|PinLength=30|Location.X=490|Location.Y=678|Name=63|Designator=63|PinPropagationDelay=0.000000E+000
|RECORD=2|OwnerIndex=348|OwnerPartId=1|FormalType=1|PinConglomerate=24|PinLength=30|Location.X=550|Location.Y=678|Name=64|Designator=64|PinPropagationDelay=0.000000E+000
|RECORD=2|OwnerIndex=348|OwnerPartId=1|FormalType=1|PinConglomerate=26|PinLength=30|Location.X=490|Location.Y=668|Name=65|Designator=65|PinPropagationDelay=0.000000E+000
|RECORD=2|OwnerIndex=348|OwnerPartId=1|FormalType=1|PinConglomerate=24|PinLength=30|Location.X=550|Location.Y=668|Name=66|Designator=66|PinPropagationDelay=0.000000E+000
|RECORD=2|OwnerIndex=348|OwnerPartId=1|FormalType=1|PinConglomerate=26|PinLength=30|Location.X=490|Location.Y=658|Name=67|Designator=67|PinPropagationDelay=0.000000E+000
|RECORD=2|OwnerIndex=348|OwnerPartId=1|FormalType=1|PinConglomerate=24|PinLength=30|Location.X=550|Location.Y=658|Name=68|Designator=68|PinPropagationDelay=0.000000E+000
|RECORD=2|OwnerIndex=348|OwnerPartId=1|FormalType=1|PinConglomerate=26|PinLength=30|Location.X=490|Location.Y=648|Name=69|Designator=69|PinPropagationDelay=0.000000E+000
|RECORD=2|OwnerIndex=348|OwnerPartId=1|FormalType=1|PinConglomerate=24|PinLength=30|Location.X=550|Location.Y=648|Name=70|Designator=70|PinPropagationDelay=0.000000E+000
|RECORD=2|OwnerIndex=348|OwnerPartId=1|FormalType=1|PinConglomerate=26|PinLength=30|Location.X=490|Location.Y=638|Name=71|Designator=71|PinPropagationDelay=0.000000E+000
|RECORD=2|OwnerIndex=348|OwnerPartId=1|FormalType=1|PinConglomerate=24|PinLength=30|Location.X=550|Location.Y=638|Name=72|Designator=72|PinPropagationDelay=0.000000E+000
|RECORD=2|OwnerIndex=348|OwnerPartId=1|FormalType=1|PinConglomerate=26|PinLength=30|Location.X=490|Location.Y=628|Name=73|Designator=73|PinPropagationDelay=0.000000E+000
|RECORD=2|OwnerIndex=348|OwnerPartId=1|FormalType=1|PinConglomerate=24|PinLength=30|Location.X=550|Location.Y=628|Name=74|Designator=74|PinPropagationDelay=0.000000E+000
|RECORD=2|OwnerIndex=348|OwnerPartId=1|FormalType=1|PinConglomerate=26|PinLength=30|Location.X=490|Location.Y=618|Name=75|Designator=75|PinPropagationDelay=0.000000E+000
|RECORD=2|OwnerIndex=348|OwnerPartId=1|FormalType=1|PinConglomerate=24|PinLength=30|Location.X=550|Location.Y=618|Name=76|Designator=76|PinPropagationDelay=0.000000E+000
|RECORD=2|OwnerIndex=348|OwnerPartId=1|FormalType=1|PinConglomerate=26|PinLength=30|Location.X=490|Location.Y=608|Name=77|Designator=77|PinPropagationDelay=0.000000E+000
|RECORD=2|OwnerIndex=348|OwnerPartId=1|FormalType=1|PinConglomerate=24|PinLength=30|Location.X=550|Location.Y=608|Name=78|Designator=78|PinPropagationDelay=0.000000E+000
|RECORD=2|OwnerIndex=348|OwnerPartId=1|FormalType=1|PinConglomerate=26|PinLength=30|Location.X=490|Location.Y=598|Name=79|Designator=79|PinPropagationDelay=0.000000E+000
|RECORD=2|OwnerIndex=348|OwnerPartId=1|FormalType=1|PinConglomerate=24|PinLength=30|Location.X=550|Location.Y=598|Name=80|Designator=80|PinPropagationDelay=0.000000E+000
|RECORD=2|OwnerIndex=348|OwnerPartId=1|FormalType=1|PinConglomerate=26|PinLength=30|Location.X=490|Location.Y=588|Name=81|Designator=81|PinPropagationDelay=0.000000E+000
|RECORD=2|OwnerIndex=348|OwnerPartId=1|FormalType=1|PinConglomerate=24|PinLength=30|Location.X=550|Location.Y=588|Name=82|Designator=82|PinPropagationDelay=0.000000E+000
|RECORD=2|OwnerIndex=348|OwnerPartId=1|FormalType=1|PinConglomerate=26|PinLength=30|Location.X=490|Location.Y=578|Name=83|Designator=83|PinPropagationDelay=0.000000E+000
|RECORD=2|OwnerIndex=348|OwnerPartId=1|FormalType=1|PinConglomerate=24|PinLength=30|Location.X=550|Location.Y=578|Name=84|Designator=84|PinPropagationDelay=0.000000E+000
|RECORD=34|OwnerIndex=348|IndexInSheet=-1|OwnerPartId=-1|Location.X=490|Location.Y=998|Color=8388608|FontID=1|Text=J34|Name=Designator|ReadOnlyState=1
|RECORD=41|OwnerIndex=348|IndexInSheet=-1|OwnerPartId=-1|Location.X=490|Location.Y=558|Color=8388608|FontID=1|Text=Single FPGA Conn|Name=Comment
|RECORD=44|OwnerIndex=348
|RECORD=45|OwnerIndex=523|IndexInSheet=-1|ModelName=SingleFPGAConn|ModelType=PCBLIB|DatafileCount=1|ModelDatafileEntity0=SingleFPGAConn|ModelDatafileKind0=PCBLib|IsCurrent=T
|RECORD=46|OwnerIndex=524
|RECORD=48|OwnerIndex=524
|RECORD=1|LibReference=Single FPGA Conn|PartCount=2|DisplayModeCount=1|IndexInSheet=315|OwnerPartId=-1|Location.X=460|Location.Y=88|CurrentPartId=1|LibraryPath=*|SourceLibraryName=FPGA_CONN.SchLib|TargetFileName=*|AreaColor=11599871|Color=128|PartIDLocked=T|PinsMoveable=T|DesignItemId=Single FPGA Conn|AllPinCount=84
|RECORD=41|OwnerIndex=527|OwnerPartId=-1|Location.X=455|Location.Y=508|Color=8388608|FontID=1|IsHidden=T|Text=Digi-Key|Name=Supplier 1|ReadOnlyState=3
|RECORD=41|OwnerIndex=527|IndexInSheet=1|OwnerPartId=-1|Location.X=490|Location.Y=508|Color=8388608|FontID=1|IsHidden=T|Text=255-3246-1-ND|Name=Supplier Part Number 1|ReadOnlyState=3
|RECORD=41|OwnerIndex=527|IndexInSheet=2|OwnerPartId=-1|Location.X=490|Location.Y=58|Color=8388608|FontID=1|Text=AXK680347YG|Name=Part Number
|RECORD=14|OwnerIndex=527|IsNotAccesible=T|IndexInSheet=3|OwnerPartId=1|Location.X=490|Location.Y=78|Corner.X=550|Corner.Y=508|Color=128|AreaColor=11599871|IsSolid=T
|RECORD=2|OwnerIndex=527|OwnerPartId=1|FormalType=1|PinConglomerate=26|PinLength=30|Location.X=490|Location.Y=498|Name=1|Designator=1|PinPropagationDelay=0.000000E+000
|RECORD=2|OwnerIndex=527|OwnerPartId=1|FormalType=1|PinConglomerate=24|PinLength=30|Location.X=550|Location.Y=498|Name=2|Designator=2|PinPropagationDelay=0.000000E+000
|RECORD=2|OwnerIndex=527|OwnerPartId=1|FormalType=1|PinConglomerate=26|PinLength=30|Location.X=490|Location.Y=488|Name=3|Designator=3|PinPropagationDelay=0.000000E+000
|RECORD=2|OwnerIndex=527|OwnerPartId=1|FormalType=1|PinConglomerate=24|PinLength=30|Location.X=550|Location.Y=488|Name=4|Designator=4|PinPropagationDelay=0.000000E+000
|RECORD=2|OwnerIndex=527|OwnerPartId=1|FormalType=1|PinConglomerate=26|PinLength=30|Location.X=490|Location.Y=478|Name=5|Designator=5|PinPropagationDelay=0.000000E+000
|RECORD=2|OwnerIndex=527|OwnerPartId=1|FormalType=1|PinConglomerate=24|PinLength=30|Location.X=550|Location.Y=478|Name=6|Designator=6|PinPropagationDelay=0.000000E+000
|RECORD=2|OwnerIndex=527|OwnerPartId=1|FormalType=1|PinConglomerate=26|PinLength=30|Location.X=490|Location.Y=468|Name=7|Designator=7|PinPropagationDelay=0.000000E+000
|RECORD=2|OwnerIndex=527|OwnerPartId=1|FormalType=1|PinConglomerate=24|PinLength=30|Location.X=550|Location.Y=468|Name=8|Designator=8|PinPropagationDelay=0.000000E+000
|RECORD=2|OwnerIndex=527|OwnerPartId=1|FormalType=1|PinConglomerate=26|PinLength=30|Location.X=490|Location.Y=458|Name=9|Designator=9|PinPropagationDelay=0.000000E+000
|RECORD=2|OwnerIndex=527|OwnerPartId=1|FormalType=1|PinConglomerate=24|PinLength=30|Location.X=550|Location.Y=458|Name=10|Designator=10|PinPropagationDelay=0.000000E+000
|RECORD=2|OwnerIndex=527|OwnerPartId=1|FormalType=1|PinConglomerate=26|PinLength=30|Location.X=490|Location.Y=448|Name=11|Designator=11|PinPropagationDelay=0.000000E+000
|RECORD=2|OwnerIndex=527|OwnerPartId=1|FormalType=1|PinConglomerate=24|PinLength=30|Location.X=550|Location.Y=448|Name=12|Designator=12|PinPropagationDelay=0.000000E+000
|RECORD=2|OwnerIndex=527|OwnerPartId=1|FormalType=1|PinConglomerate=26|PinLength=30|Location.X=490|Location.Y=438|Name=13|Designator=13|PinPropagationDelay=0.000000E+000
|RECORD=2|OwnerIndex=527|OwnerPartId=1|FormalType=1|PinConglomerate=24|PinLength=30|Location.X=550|Location.Y=438|Name=14|Designator=14|PinPropagationDelay=0.000000E+000
|RECORD=2|OwnerIndex=527|OwnerPartId=1|FormalType=1|PinConglomerate=26|PinLength=30|Location.X=490|Location.Y=428|Name=15|Designator=15|PinPropagationDelay=0.000000E+000
|RECORD=2|OwnerIndex=527|OwnerPartId=1|FormalType=1|PinConglomerate=24|PinLength=30|Location.X=550|Location.Y=428|Name=16|Designator=16|PinPropagationDelay=0.000000E+000
|RECORD=2|OwnerIndex=527|OwnerPartId=1|FormalType=1|PinConglomerate=26|PinLength=30|Location.X=490|Location.Y=418|Name=17|Designator=17|PinPropagationDelay=0.000000E+000
|RECORD=2|OwnerIndex=527|OwnerPartId=1|FormalType=1|PinConglomerate=24|PinLength=30|Location.X=550|Location.Y=418|Name=18|Designator=18|PinPropagationDelay=0.000000E+000
|RECORD=2|OwnerIndex=527|OwnerPartId=1|FormalType=1|PinConglomerate=26|PinLength=30|Location.X=490|Location.Y=408|Name=19|Designator=19|PinPropagationDelay=0.000000E+000
|RECORD=2|OwnerIndex=527|OwnerPartId=1|FormalType=1|PinConglomerate=24|PinLength=30|Location.X=550|Location.Y=408|Name=20|Designator=20|PinPropagationDelay=0.000000E+000
|RECORD=2|OwnerIndex=527|OwnerPartId=1|FormalType=1|PinConglomerate=26|PinLength=30|Location.X=490|Location.Y=398|Name=21|Designator=21|PinPropagationDelay=0.000000E+000
|RECORD=2|OwnerIndex=527|OwnerPartId=1|FormalType=1|PinConglomerate=24|PinLength=30|Location.X=550|Location.Y=398|Name=22|Designator=22|PinPropagationDelay=0.000000E+000
|RECORD=2|OwnerIndex=527|OwnerPartId=1|FormalType=1|PinConglomerate=26|PinLength=30|Location.X=490|Location.Y=388|Name=23|Designator=23|PinPropagationDelay=0.000000E+000
|RECORD=2|OwnerIndex=527|OwnerPartId=1|FormalType=1|PinConglomerate=24|PinLength=30|Location.X=550|Location.Y=388|Name=24|Designator=24|PinPropagationDelay=0.000000E+000
|RECORD=2|OwnerIndex=527|OwnerPartId=1|FormalType=1|PinConglomerate=26|PinLength=30|Location.X=490|Location.Y=378|Name=25|Designator=25|PinPropagationDelay=0.000000E+000
|RECORD=2|OwnerIndex=527|OwnerPartId=1|FormalType=1|PinConglomerate=24|PinLength=30|Location.X=550|Location.Y=378|Name=26|Designator=26|PinPropagationDelay=0.000000E+000
|RECORD=2|OwnerIndex=527|OwnerPartId=1|FormalType=1|PinConglomerate=26|PinLength=30|Location.X=490|Location.Y=368|Name=27|Designator=27|PinPropagationDelay=0.000000E+000
|RECORD=2|OwnerIndex=527|OwnerPartId=1|FormalType=1|PinConglomerate=24|PinLength=30|Location.X=550|Location.Y=368|Name=28|Designator=28|PinPropagationDelay=0.000000E+000
|RECORD=2|OwnerIndex=527|OwnerPartId=1|FormalType=1|PinConglomerate=26|PinLength=30|Location.X=490|Location.Y=358|Name=29|Designator=29|PinPropagationDelay=0.000000E+000
|RECORD=2|OwnerIndex=527|OwnerPartId=1|FormalType=1|PinConglomerate=24|PinLength=30|Location.X=550|Location.Y=358|Name=30|Designator=30|PinPropagationDelay=0.000000E+000
|RECORD=2|OwnerIndex=527|OwnerPartId=1|FormalType=1|PinConglomerate=26|PinLength=30|Location.X=490|Location.Y=348|Name=31|Designator=31|PinPropagationDelay=0.000000E+000
|RECORD=2|OwnerIndex=527|OwnerPartId=1|FormalType=1|PinConglomerate=24|PinLength=30|Location.X=550|Location.Y=348|Name=32|Designator=32|PinPropagationDelay=0.000000E+000
|RECORD=2|OwnerIndex=527|OwnerPartId=1|FormalType=1|PinConglomerate=26|PinLength=30|Location.X=490|Location.Y=338|Name=33|Designator=33|PinPropagationDelay=0.000000E+000
|RECORD=2|OwnerIndex=527|OwnerPartId=1|FormalType=1|PinConglomerate=24|PinLength=30|Location.X=550|Location.Y=338|Name=34|Designator=34|PinPropagationDelay=0.000000E+000
|RECORD=2|OwnerIndex=527|OwnerPartId=1|FormalType=1|PinConglomerate=26|PinLength=30|Location.X=490|Location.Y=328|Name=35|Designator=35|PinPropagationDelay=0.000000E+000
|RECORD=2|OwnerIndex=527|OwnerPartId=1|FormalType=1|PinConglomerate=24|PinLength=30|Location.X=550|Location.Y=328|Name=36|Designator=36|PinPropagationDelay=0.000000E+000
|RECORD=2|OwnerIndex=527|OwnerPartId=1|FormalType=1|PinConglomerate=26|PinLength=30|Location.X=490|Location.Y=318|Name=37|Designator=37|PinPropagationDelay=0.000000E+000
|RECORD=2|OwnerIndex=527|OwnerPartId=1|FormalType=1|PinConglomerate=24|PinLength=30|Location.X=550|Location.Y=318|Name=38|Designator=38|PinPropagationDelay=0.000000E+000
|RECORD=2|OwnerIndex=527|OwnerPartId=1|FormalType=1|PinConglomerate=26|PinLength=30|Location.X=490|Location.Y=308|Name=39|Designator=39|PinPropagationDelay=0.000000E+000
|RECORD=2|OwnerIndex=527|OwnerPartId=1|FormalType=1|PinConglomerate=24|PinLength=30|Location.X=550|Location.Y=308|Name=40|Designator=40|PinPropagationDelay=0.000000E+000
|RECORD=2|OwnerIndex=527|OwnerPartId=1|FormalType=1|PinConglomerate=26|PinLength=30|Location.X=490|Location.Y=298|Name=41|Designator=41|PinPropagationDelay=0.000000E+000
|RECORD=2|OwnerIndex=527|OwnerPartId=1|FormalType=1|PinConglomerate=24|PinLength=30|Location.X=550|Location.Y=298|Name=42|Designator=42|PinPropagationDelay=0.000000E+000
|RECORD=2|OwnerIndex=527|OwnerPartId=1|FormalType=1|PinConglomerate=26|PinLength=30|Location.X=490|Location.Y=288|Name=43|Designator=43|PinPropagationDelay=0.000000E+000
|RECORD=2|OwnerIndex=527|OwnerPartId=1|FormalType=1|PinConglomerate=24|PinLength=30|Location.X=550|Location.Y=288|Name=44|Designator=44|PinPropagationDelay=0.000000E+000
|RECORD=2|OwnerIndex=527|OwnerPartId=1|FormalType=1|PinConglomerate=26|PinLength=30|Location.X=490|Location.Y=278|Name=45|Designator=45|PinPropagationDelay=0.000000E+000
|RECORD=2|OwnerIndex=527|OwnerPartId=1|FormalType=1|PinConglomerate=24|PinLength=30|Location.X=550|Location.Y=278|Name=46|Designator=46|PinPropagationDelay=0.000000E+000
|RECORD=2|OwnerIndex=527|OwnerPartId=1|FormalType=1|PinConglomerate=26|PinLength=30|Location.X=490|Location.Y=268|Name=47|Designator=47|PinPropagationDelay=0.000000E+000
|RECORD=2|OwnerIndex=527|OwnerPartId=1|FormalType=1|PinConglomerate=24|PinLength=30|Location.X=550|Location.Y=268|Name=48|Designator=48|PinPropagationDelay=0.000000E+000
|RECORD=2|OwnerIndex=527|OwnerPartId=1|FormalType=1|PinConglomerate=26|PinLength=30|Location.X=490|Location.Y=258|Name=49|Designator=49|PinPropagationDelay=0.000000E+000
|RECORD=2|OwnerIndex=527|OwnerPartId=1|FormalType=1|PinConglomerate=24|PinLength=30|Location.X=550|Location.Y=258|Name=50|Designator=50|PinPropagationDelay=0.000000E+000
|RECORD=2|OwnerIndex=527|OwnerPartId=1|FormalType=1|PinConglomerate=26|PinLength=30|Location.X=490|Location.Y=248|Name=51|Designator=51|PinPropagationDelay=0.000000E+000
|RECORD=2|OwnerIndex=527|OwnerPartId=1|FormalType=1|PinConglomerate=24|PinLength=30|Location.X=550|Location.Y=248|Name=52|Designator=52|PinPropagationDelay=0.000000E+000
|RECORD=2|OwnerIndex=527|OwnerPartId=1|FormalType=1|PinConglomerate=26|PinLength=30|Location.X=490|Location.Y=238|Name=53|Designator=53|PinPropagationDelay=0.000000E+000
|RECORD=2|OwnerIndex=527|OwnerPartId=1|FormalType=1|PinConglomerate=24|PinLength=30|Location.X=550|Location.Y=238|Name=54|Designator=54|PinPropagationDelay=0.000000E+000
|RECORD=2|OwnerIndex=527|OwnerPartId=1|FormalType=1|PinConglomerate=26|PinLength=30|Location.X=490|Location.Y=228|Name=55|Designator=55|PinPropagationDelay=0.000000E+000
|RECORD=2|OwnerIndex=527|OwnerPartId=1|FormalType=1|PinConglomerate=24|PinLength=30|Location.X=550|Location.Y=228|Name=56|Designator=56|PinPropagationDelay=0.000000E+000
|RECORD=2|OwnerIndex=527|OwnerPartId=1|FormalType=1|PinConglomerate=26|PinLength=30|Location.X=490|Location.Y=218|Name=57|Designator=57|PinPropagationDelay=0.000000E+000
|RECORD=2|OwnerIndex=527|OwnerPartId=1|FormalType=1|PinConglomerate=24|PinLength=30|Location.X=550|Location.Y=218|Name=58|Designator=58|PinPropagationDelay=0.000000E+000
|RECORD=2|OwnerIndex=527|OwnerPartId=1|FormalType=1|PinConglomerate=26|PinLength=30|Location.X=490|Location.Y=208|Name=59|Designator=59|PinPropagationDelay=0.000000E+000
|RECORD=2|OwnerIndex=527|OwnerPartId=1|FormalType=1|PinConglomerate=24|PinLength=30|Location.X=550|Location.Y=208|Name=60|Designator=60|PinPropagationDelay=0.000000E+000
|RECORD=2|OwnerIndex=527|OwnerPartId=1|FormalType=1|PinConglomerate=26|PinLength=30|Location.X=490|Location.Y=198|Name=61|Designator=61|PinPropagationDelay=0.000000E+000
|RECORD=2|OwnerIndex=527|OwnerPartId=1|FormalType=1|PinConglomerate=24|PinLength=30|Location.X=550|Location.Y=198|Name=62|Designator=62|PinPropagationDelay=0.000000E+000
|RECORD=2|OwnerIndex=527|OwnerPartId=1|FormalType=1|PinConglomerate=26|PinLength=30|Location.X=490|Location.Y=188|Name=63|Designator=63|PinPropagationDelay=0.000000E+000
|RECORD=2|OwnerIndex=527|OwnerPartId=1|FormalType=1|PinConglomerate=24|PinLength=30|Location.X=550|Location.Y=188|Name=64|Designator=64|PinPropagationDelay=0.000000E+000
|RECORD=2|OwnerIndex=527|OwnerPartId=1|FormalType=1|PinConglomerate=26|PinLength=30|Location.X=490|Location.Y=178|Name=65|Designator=65|PinPropagationDelay=0.000000E+000
|RECORD=2|OwnerIndex=527|OwnerPartId=1|FormalType=1|PinConglomerate=24|PinLength=30|Location.X=550|Location.Y=178|Name=66|Designator=66|PinPropagationDelay=0.000000E+000
|RECORD=2|OwnerIndex=527|OwnerPartId=1|FormalType=1|PinConglomerate=26|PinLength=30|Location.X=490|Location.Y=168|Name=67|Designator=67|PinPropagationDelay=0.000000E+000
|RECORD=2|OwnerIndex=527|OwnerPartId=1|FormalType=1|PinConglomerate=24|PinLength=30|Location.X=550|Location.Y=168|Name=68|Designator=68|PinPropagationDelay=0.000000E+000
|RECORD=2|OwnerIndex=527|OwnerPartId=1|FormalType=1|PinConglomerate=26|PinLength=30|Location.X=490|Location.Y=158|Name=69|Designator=69|PinPropagationDelay=0.000000E+000
|RECORD=2|OwnerIndex=527|OwnerPartId=1|FormalType=1|PinConglomerate=24|PinLength=30|Location.X=550|Location.Y=158|Name=70|Designator=70|PinPropagationDelay=0.000000E+000
|RECORD=2|OwnerIndex=527|OwnerPartId=1|FormalType=1|PinConglomerate=26|PinLength=30|Location.X=490|Location.Y=148|Name=71|Designator=71|PinPropagationDelay=0.000000E+000
|RECORD=2|OwnerIndex=527|OwnerPartId=1|FormalType=1|PinConglomerate=24|PinLength=30|Location.X=550|Location.Y=148|Name=72|Designator=72|PinPropagationDelay=0.000000E+000
|RECORD=2|OwnerIndex=527|OwnerPartId=1|FormalType=1|PinConglomerate=26|PinLength=30|Location.X=490|Location.Y=138|Name=73|Designator=73|PinPropagationDelay=0.000000E+000
|RECORD=2|OwnerIndex=527|OwnerPartId=1|FormalType=1|PinConglomerate=24|PinLength=30|Location.X=550|Location.Y=138|Name=74|Designator=74|PinPropagationDelay=0.000000E+000
|RECORD=2|OwnerIndex=527|OwnerPartId=1|FormalType=1|PinConglomerate=26|PinLength=30|Location.X=490|Location.Y=128|Name=75|Designator=75|PinPropagationDelay=0.000000E+000
|RECORD=2|OwnerIndex=527|OwnerPartId=1|FormalType=1|PinConglomerate=24|PinLength=30|Location.X=550|Location.Y=128|Name=76|Designator=76|PinPropagationDelay=0.000000E+000
|RECORD=2|OwnerIndex=527|OwnerPartId=1|FormalType=1|PinConglomerate=26|PinLength=30|Location.X=490|Location.Y=118|Name=77|Designator=77|PinPropagationDelay=0.000000E+000
|RECORD=2|OwnerIndex=527|OwnerPartId=1|FormalType=1|PinConglomerate=24|PinLength=30|Location.X=550|Location.Y=118|Name=78|Designator=78|PinPropagationDelay=0.000000E+000
|RECORD=2|OwnerIndex=527|OwnerPartId=1|FormalType=1|PinConglomerate=26|PinLength=30|Location.X=490|Location.Y=108|Name=79|Designator=79|PinPropagationDelay=0.000000E+000
|RECORD=2|OwnerIndex=527|OwnerPartId=1|FormalType=1|PinConglomerate=24|PinLength=30|Location.X=550|Location.Y=108|Name=80|Designator=80|PinPropagationDelay=0.000000E+000
|RECORD=2|OwnerIndex=527|OwnerPartId=1|FormalType=1|PinConglomerate=26|PinLength=30|Location.X=490|Location.Y=98|Name=81|Designator=81|PinPropagationDelay=0.000000E+000
|RECORD=2|OwnerIndex=527|OwnerPartId=1|FormalType=1|PinConglomerate=24|PinLength=30|Location.X=550|Location.Y=98|Name=82|Designator=82|PinPropagationDelay=0.000000E+000
|RECORD=2|OwnerIndex=527|OwnerPartId=1|FormalType=1|PinConglomerate=26|PinLength=30|Location.X=490|Location.Y=88|Name=83|Designator=83|PinPropagationDelay=0.000000E+000
|RECORD=2|OwnerIndex=527|OwnerPartId=1|FormalType=1|PinConglomerate=24|PinLength=30|Location.X=550|Location.Y=88|Name=84|Designator=84|PinPropagationDelay=0.000000E+000
|RECORD=34|OwnerIndex=527|IndexInSheet=-1|OwnerPartId=-1|Location.X=490|Location.Y=508|Color=8388608|FontID=1|Text=J36|Name=Designator|ReadOnlyState=1
|RECORD=41|OwnerIndex=527|IndexInSheet=-1|OwnerPartId=-1|Location.X=490|Location.Y=68|Color=8388608|FontID=1|Text=Single FPGA Conn|Name=Comment
|RECORD=44|OwnerIndex=527
|RECORD=45|OwnerIndex=702|IndexInSheet=-1|ModelName=SingleFPGAConn|ModelType=PCBLIB|DatafileCount=1|ModelDatafileEntity0=SingleFPGAConn|ModelDatafileKind0=PCBLib|IsCurrent=T
|RECORD=46|OwnerIndex=703
|RECORD=48|OwnerIndex=703
|RECORD=1|LibReference=Single FPGA Conn|PartCount=2|DisplayModeCount=1|IndexInSheet=316|OwnerPartId=-1|Location.X=1170|Location.Y=578|CurrentPartId=1|LibraryPath=*|SourceLibraryName=FPGA_CONN.SchLib|TargetFileName=*|AreaColor=11599871|Color=128|PartIDLocked=T|PinsMoveable=T|DesignItemId=Single FPGA Conn|AllPinCount=84
|RECORD=41|OwnerIndex=706|OwnerPartId=-1|Location.X=1165|Location.Y=998|Color=8388608|FontID=1|IsHidden=T|Text=Digi-Key|Name=Supplier 1|ReadOnlyState=3
|RECORD=41|OwnerIndex=706|IndexInSheet=1|OwnerPartId=-1|Location.X=1200|Location.Y=998|Color=8388608|FontID=1|IsHidden=T|Text=255-3246-1-ND|Name=Supplier Part Number 1|ReadOnlyState=3
|RECORD=41|OwnerIndex=706|IndexInSheet=2|OwnerPartId=-1|Location.X=1200|Location.Y=548|Color=8388608|FontID=1|Text=AXK680347YG|Name=Part Number
|RECORD=14|OwnerIndex=706|IsNotAccesible=T|IndexInSheet=3|OwnerPartId=1|Location.X=1200|Location.Y=568|Corner.X=1260|Corner.Y=998|Color=128|AreaColor=11599871|IsSolid=T
|RECORD=2|OwnerIndex=706|OwnerPartId=1|FormalType=1|PinConglomerate=26|PinLength=30|Location.X=1200|Location.Y=988|Name=1|Designator=1|PinPropagationDelay=0.000000E+000
|RECORD=2|OwnerIndex=706|OwnerPartId=1|FormalType=1|PinConglomerate=24|PinLength=30|Location.X=1260|Location.Y=988|Name=2|Designator=2|PinPropagationDelay=0.000000E+000
|RECORD=2|OwnerIndex=706|OwnerPartId=1|FormalType=1|PinConglomerate=26|PinLength=30|Location.X=1200|Location.Y=978|Name=3|Designator=3|PinPropagationDelay=0.000000E+000
|RECORD=2|OwnerIndex=706|OwnerPartId=1|FormalType=1|PinConglomerate=24|PinLength=30|Location.X=1260|Location.Y=978|Name=4|Designator=4|PinPropagationDelay=0.000000E+000
|RECORD=2|OwnerIndex=706|OwnerPartId=1|FormalType=1|PinConglomerate=26|PinLength=30|Location.X=1200|Location.Y=968|Name=5|Designator=5|PinPropagationDelay=0.000000E+000
|RECORD=2|OwnerIndex=706|OwnerPartId=1|FormalType=1|PinConglomerate=24|PinLength=30|Location.X=1260|Location.Y=968|Name=6|Designator=6|PinPropagationDelay=0.000000E+000
|RECORD=2|OwnerIndex=706|OwnerPartId=1|FormalType=1|PinConglomerate=26|PinLength=30|Location.X=1200|Location.Y=958|Name=7|Designator=7|PinPropagationDelay=0.000000E+000
|RECORD=2|OwnerIndex=706|OwnerPartId=1|FormalType=1|PinConglomerate=24|PinLength=30|Location.X=1260|Location.Y=958|Name=8|Designator=8|PinPropagationDelay=0.000000E+000
|RECORD=2|OwnerIndex=706|OwnerPartId=1|FormalType=1|PinConglomerate=26|PinLength=30|Location.X=1200|Location.Y=948|Name=9|Designator=9|PinPropagationDelay=0.000000E+000
|RECORD=2|OwnerIndex=706|OwnerPartId=1|FormalType=1|PinConglomerate=24|PinLength=30|Location.X=1260|Location.Y=948|Name=10|Designator=10|PinPropagationDelay=0.000000E+000
|RECORD=2|OwnerIndex=706|OwnerPartId=1|FormalType=1|PinConglomerate=26|PinLength=30|Location.X=1200|Location.Y=938|Name=11|Designator=11|PinPropagationDelay=0.000000E+000
|RECORD=2|OwnerIndex=706|OwnerPartId=1|FormalType=1|PinConglomerate=24|PinLength=30|Location.X=1260|Location.Y=938|Name=12|Designator=12|PinPropagationDelay=0.000000E+000
|RECORD=2|OwnerIndex=706|OwnerPartId=1|FormalType=1|PinConglomerate=26|PinLength=30|Location.X=1200|Location.Y=928|Name=13|Designator=13|PinPropagationDelay=0.000000E+000
|RECORD=2|OwnerIndex=706|OwnerPartId=1|FormalType=1|PinConglomerate=24|PinLength=30|Location.X=1260|Location.Y=928|Name=14|Designator=14|PinPropagationDelay=0.000000E+000
|RECORD=2|OwnerIndex=706|OwnerPartId=1|FormalType=1|PinConglomerate=26|PinLength=30|Location.X=1200|Location.Y=918|Name=15|Designator=15|PinPropagationDelay=0.000000E+000
|RECORD=2|OwnerIndex=706|OwnerPartId=1|FormalType=1|PinConglomerate=24|PinLength=30|Location.X=1260|Location.Y=918|Name=16|Designator=16|PinPropagationDelay=0.000000E+000
|RECORD=2|OwnerIndex=706|OwnerPartId=1|FormalType=1|PinConglomerate=26|PinLength=30|Location.X=1200|Location.Y=908|Name=17|Designator=17|PinPropagationDelay=0.000000E+000
|RECORD=2|OwnerIndex=706|OwnerPartId=1|FormalType=1|PinConglomerate=24|PinLength=30|Location.X=1260|Location.Y=908|Name=18|Designator=18|PinPropagationDelay=0.000000E+000
|RECORD=2|OwnerIndex=706|OwnerPartId=1|FormalType=1|PinConglomerate=26|PinLength=30|Location.X=1200|Location.Y=898|Name=19|Designator=19|PinPropagationDelay=0.000000E+000
|RECORD=2|OwnerIndex=706|OwnerPartId=1|FormalType=1|PinConglomerate=24|PinLength=30|Location.X=1260|Location.Y=898|Name=20|Designator=20|PinPropagationDelay=0.000000E+000
|RECORD=2|OwnerIndex=706|OwnerPartId=1|FormalType=1|PinConglomerate=26|PinLength=30|Location.X=1200|Location.Y=888|Name=21|Designator=21|PinPropagationDelay=0.000000E+000
|RECORD=2|OwnerIndex=706|OwnerPartId=1|FormalType=1|PinConglomerate=24|PinLength=30|Location.X=1260|Location.Y=888|Name=22|Designator=22|PinPropagationDelay=0.000000E+000
|RECORD=2|OwnerIndex=706|OwnerPartId=1|FormalType=1|PinConglomerate=26|PinLength=30|Location.X=1200|Location.Y=878|Name=23|Designator=23|PinPropagationDelay=0.000000E+000
|RECORD=2|OwnerIndex=706|OwnerPartId=1|FormalType=1|PinConglomerate=24|PinLength=30|Location.X=1260|Location.Y=878|Name=24|Designator=24|PinPropagationDelay=0.000000E+000
|RECORD=2|OwnerIndex=706|OwnerPartId=1|FormalType=1|PinConglomerate=26|PinLength=30|Location.X=1200|Location.Y=868|Name=25|Designator=25|PinPropagationDelay=0.000000E+000
|RECORD=2|OwnerIndex=706|OwnerPartId=1|FormalType=1|PinConglomerate=24|PinLength=30|Location.X=1260|Location.Y=868|Name=26|Designator=26|PinPropagationDelay=0.000000E+000
|RECORD=2|OwnerIndex=706|OwnerPartId=1|FormalType=1|PinConglomerate=26|PinLength=30|Location.X=1200|Location.Y=858|Name=27|Designator=27|PinPropagationDelay=0.000000E+000
|RECORD=2|OwnerIndex=706|OwnerPartId=1|FormalType=1|PinConglomerate=24|PinLength=30|Location.X=1260|Location.Y=858|Name=28|Designator=28|PinPropagationDelay=0.000000E+000
|RECORD=2|OwnerIndex=706|OwnerPartId=1|FormalType=1|PinConglomerate=26|PinLength=30|Location.X=1200|Location.Y=848|Name=29|Designator=29|PinPropagationDelay=0.000000E+000
|RECORD=2|OwnerIndex=706|OwnerPartId=1|FormalType=1|PinConglomerate=24|PinLength=30|Location.X=1260|Location.Y=848|Name=30|Designator=30|PinPropagationDelay=0.000000E+000
|RECORD=2|OwnerIndex=706|OwnerPartId=1|FormalType=1|PinConglomerate=26|PinLength=30|Location.X=1200|Location.Y=838|Name=31|Designator=31|PinPropagationDelay=0.000000E+000
|RECORD=2|OwnerIndex=706|OwnerPartId=1|FormalType=1|PinConglomerate=24|PinLength=30|Location.X=1260|Location.Y=838|Name=32|Designator=32|PinPropagationDelay=0.000000E+000
|RECORD=2|OwnerIndex=706|OwnerPartId=1|FormalType=1|PinConglomerate=26|PinLength=30|Location.X=1200|Location.Y=828|Name=33|Designator=33|PinPropagationDelay=0.000000E+000
|RECORD=2|OwnerIndex=706|OwnerPartId=1|FormalType=1|PinConglomerate=24|PinLength=30|Location.X=1260|Location.Y=828|Name=34|Designator=34|PinPropagationDelay=0.000000E+000
|RECORD=2|OwnerIndex=706|OwnerPartId=1|FormalType=1|PinConglomerate=26|PinLength=30|Location.X=1200|Location.Y=818|Name=35|Designator=35|PinPropagationDelay=0.000000E+000
|RECORD=2|OwnerIndex=706|OwnerPartId=1|FormalType=1|PinConglomerate=24|PinLength=30|Location.X=1260|Location.Y=818|Name=36|Designator=36|PinPropagationDelay=0.000000E+000
|RECORD=2|OwnerIndex=706|OwnerPartId=1|FormalType=1|PinConglomerate=26|PinLength=30|Location.X=1200|Location.Y=808|Name=37|Designator=37|PinPropagationDelay=0.000000E+000
|RECORD=2|OwnerIndex=706|OwnerPartId=1|FormalType=1|PinConglomerate=24|PinLength=30|Location.X=1260|Location.Y=808|Name=38|Designator=38|PinPropagationDelay=0.000000E+000
|RECORD=2|OwnerIndex=706|OwnerPartId=1|FormalType=1|PinConglomerate=26|PinLength=30|Location.X=1200|Location.Y=798|Name=39|Designator=39|PinPropagationDelay=0.000000E+000
|RECORD=2|OwnerIndex=706|OwnerPartId=1|FormalType=1|PinConglomerate=24|PinLength=30|Location.X=1260|Location.Y=798|Name=40|Designator=40|PinPropagationDelay=0.000000E+000
|RECORD=2|OwnerIndex=706|OwnerPartId=1|FormalType=1|PinConglomerate=26|PinLength=30|Location.X=1200|Location.Y=788|Name=41|Designator=41|PinPropagationDelay=0.000000E+000
|RECORD=2|OwnerIndex=706|OwnerPartId=1|FormalType=1|PinConglomerate=24|PinLength=30|Location.X=1260|Location.Y=788|Name=42|Designator=42|PinPropagationDelay=0.000000E+000
|RECORD=2|OwnerIndex=706|OwnerPartId=1|FormalType=1|PinConglomerate=26|PinLength=30|Location.X=1200|Location.Y=778|Name=43|Designator=43|PinPropagationDelay=0.000000E+000
|RECORD=2|OwnerIndex=706|OwnerPartId=1|FormalType=1|PinConglomerate=24|PinLength=30|Location.X=1260|Location.Y=778|Name=44|Designator=44|PinPropagationDelay=0.000000E+000
|RECORD=2|OwnerIndex=706|OwnerPartId=1|FormalType=1|PinConglomerate=26|PinLength=30|Location.X=1200|Location.Y=768|Name=45|Designator=45|PinPropagationDelay=0.000000E+000
|RECORD=2|OwnerIndex=706|OwnerPartId=1|FormalType=1|PinConglomerate=24|PinLength=30|Location.X=1260|Location.Y=768|Name=46|Designator=46|PinPropagationDelay=0.000000E+000
|RECORD=2|OwnerIndex=706|OwnerPartId=1|FormalType=1|PinConglomerate=26|PinLength=30|Location.X=1200|Location.Y=758|Name=47|Designator=47|PinPropagationDelay=0.000000E+000
|RECORD=2|OwnerIndex=706|OwnerPartId=1|FormalType=1|PinConglomerate=24|PinLength=30|Location.X=1260|Location.Y=758|Name=48|Designator=48|PinPropagationDelay=0.000000E+000
|RECORD=2|OwnerIndex=706|OwnerPartId=1|FormalType=1|PinConglomerate=26|PinLength=30|Location.X=1200|Location.Y=748|Name=49|Designator=49|PinPropagationDelay=0.000000E+000
|RECORD=2|OwnerIndex=706|OwnerPartId=1|FormalType=1|PinConglomerate=24|PinLength=30|Location.X=1260|Location.Y=748|Name=50|Designator=50|PinPropagationDelay=0.000000E+000
|RECORD=2|OwnerIndex=706|OwnerPartId=1|FormalType=1|PinConglomerate=26|PinLength=30|Location.X=1200|Location.Y=738|Name=51|Designator=51|PinPropagationDelay=0.000000E+000
|RECORD=2|OwnerIndex=706|OwnerPartId=1|FormalType=1|PinConglomerate=24|PinLength=30|Location.X=1260|Location.Y=738|Name=52|Designator=52|PinPropagationDelay=0.000000E+000
|RECORD=2|OwnerIndex=706|OwnerPartId=1|FormalType=1|PinConglomerate=26|PinLength=30|Location.X=1200|Location.Y=728|Name=53|Designator=53|PinPropagationDelay=0.000000E+000
|RECORD=2|OwnerIndex=706|OwnerPartId=1|FormalType=1|PinConglomerate=24|PinLength=30|Location.X=1260|Location.Y=728|Name=54|Designator=54|PinPropagationDelay=0.000000E+000
|RECORD=2|OwnerIndex=706|OwnerPartId=1|FormalType=1|PinConglomerate=26|PinLength=30|Location.X=1200|Location.Y=718|Name=55|Designator=55|PinPropagationDelay=0.000000E+000
|RECORD=2|OwnerIndex=706|OwnerPartId=1|FormalType=1|PinConglomerate=24|PinLength=30|Location.X=1260|Location.Y=718|Name=56|Designator=56|PinPropagationDelay=0.000000E+000
|RECORD=2|OwnerIndex=706|OwnerPartId=1|FormalType=1|PinConglomerate=26|PinLength=30|Location.X=1200|Location.Y=708|Name=57|Designator=57|PinPropagationDelay=0.000000E+000
|RECORD=2|OwnerIndex=706|OwnerPartId=1|FormalType=1|PinConglomerate=24|PinLength=30|Location.X=1260|Location.Y=708|Name=58|Designator=58|PinPropagationDelay=0.000000E+000
|RECORD=2|OwnerIndex=706|OwnerPartId=1|FormalType=1|PinConglomerate=26|PinLength=30|Location.X=1200|Location.Y=698|Name=59|Designator=59|PinPropagationDelay=0.000000E+000
|RECORD=2|OwnerIndex=706|OwnerPartId=1|FormalType=1|PinConglomerate=24|PinLength=30|Location.X=1260|Location.Y=698|Name=60|Designator=60|PinPropagationDelay=0.000000E+000
|RECORD=2|OwnerIndex=706|OwnerPartId=1|FormalType=1|PinConglomerate=26|PinLength=30|Location.X=1200|Location.Y=688|Name=61|Designator=61|PinPropagationDelay=0.000000E+000
|RECORD=2|OwnerIndex=706|OwnerPartId=1|FormalType=1|PinConglomerate=24|PinLength=30|Location.X=1260|Location.Y=688|Name=62|Designator=62|PinPropagationDelay=0.000000E+000
|RECORD=2|OwnerIndex=706|OwnerPartId=1|FormalType=1|PinConglomerate=26|PinLength=30|Location.X=1200|Location.Y=678|Name=63|Designator=63|PinPropagationDelay=0.000000E+000
|RECORD=2|OwnerIndex=706|OwnerPartId=1|FormalType=1|PinConglomerate=24|PinLength=30|Location.X=1260|Location.Y=678|Name=64|Designator=64|PinPropagationDelay=0.000000E+000
|RECORD=2|OwnerIndex=706|OwnerPartId=1|FormalType=1|PinConglomerate=26|PinLength=30|Location.X=1200|Location.Y=668|Name=65|Designator=65|PinPropagationDelay=0.000000E+000
|RECORD=2|OwnerIndex=706|OwnerPartId=1|FormalType=1|PinConglomerate=24|PinLength=30|Location.X=1260|Location.Y=668|Name=66|Designator=66|PinPropagationDelay=0.000000E+000
|RECORD=2|OwnerIndex=706|OwnerPartId=1|FormalType=1|PinConglomerate=26|PinLength=30|Location.X=1200|Location.Y=658|Name=67|Designator=67|PinPropagationDelay=0.000000E+000
|RECORD=2|OwnerIndex=706|OwnerPartId=1|FormalType=1|PinConglomerate=24|PinLength=30|Location.X=1260|Location.Y=658|Name=68|Designator=68|PinPropagationDelay=0.000000E+000
|RECORD=2|OwnerIndex=706|OwnerPartId=1|FormalType=1|PinConglomerate=26|PinLength=30|Location.X=1200|Location.Y=648|Name=69|Designator=69|PinPropagationDelay=0.000000E+000
|RECORD=2|OwnerIndex=706|OwnerPartId=1|FormalType=1|PinConglomerate=24|PinLength=30|Location.X=1260|Location.Y=648|Name=70|Designator=70|PinPropagationDelay=0.000000E+000
|RECORD=2|OwnerIndex=706|OwnerPartId=1|FormalType=1|PinConglomerate=26|PinLength=30|Location.X=1200|Location.Y=638|Name=71|Designator=71|PinPropagationDelay=0.000000E+000
|RECORD=2|OwnerIndex=706|OwnerPartId=1|FormalType=1|PinConglomerate=24|PinLength=30|Location.X=1260|Location.Y=638|Name=72|Designator=72|PinPropagationDelay=0.000000E+000
|RECORD=2|OwnerIndex=706|OwnerPartId=1|FormalType=1|PinConglomerate=26|PinLength=30|Location.X=1200|Location.Y=628|Name=73|Designator=73|PinPropagationDelay=0.000000E+000
|RECORD=2|OwnerIndex=706|OwnerPartId=1|FormalType=1|PinConglomerate=24|PinLength=30|Location.X=1260|Location.Y=628|Name=74|Designator=74|PinPropagationDelay=0.000000E+000
|RECORD=2|OwnerIndex=706|OwnerPartId=1|FormalType=1|PinConglomerate=26|PinLength=30|Location.X=1200|Location.Y=618|Name=75|Designator=75|PinPropagationDelay=0.000000E+000
|RECORD=2|OwnerIndex=706|OwnerPartId=1|FormalType=1|PinConglomerate=24|PinLength=30|Location.X=1260|Location.Y=618|Name=76|Designator=76|PinPropagationDelay=0.000000E+000
|RECORD=2|OwnerIndex=706|OwnerPartId=1|FormalType=1|PinConglomerate=26|PinLength=30|Location.X=1200|Location.Y=608|Name=77|Designator=77|PinPropagationDelay=0.000000E+000
|RECORD=2|OwnerIndex=706|OwnerPartId=1|FormalType=1|PinConglomerate=24|PinLength=30|Location.X=1260|Location.Y=608|Name=78|Designator=78|PinPropagationDelay=0.000000E+000
|RECORD=2|OwnerIndex=706|OwnerPartId=1|FormalType=1|PinConglomerate=26|PinLength=30|Location.X=1200|Location.Y=598|Name=79|Designator=79|PinPropagationDelay=0.000000E+000
|RECORD=2|OwnerIndex=706|OwnerPartId=1|FormalType=1|PinConglomerate=24|PinLength=30|Location.X=1260|Location.Y=598|Name=80|Designator=80|PinPropagationDelay=0.000000E+000
|RECORD=2|OwnerIndex=706|OwnerPartId=1|FormalType=1|PinConglomerate=26|PinLength=30|Location.X=1200|Location.Y=588|Name=81|Designator=81|PinPropagationDelay=0.000000E+000
|RECORD=2|OwnerIndex=706|OwnerPartId=1|FormalType=1|PinConglomerate=24|PinLength=30|Location.X=1260|Location.Y=588|Name=82|Designator=82|PinPropagationDelay=0.000000E+000
|RECORD=2|OwnerIndex=706|OwnerPartId=1|FormalType=1|PinConglomerate=26|PinLength=30|Location.X=1200|Location.Y=578|Name=83|Designator=83|PinPropagationDelay=0.000000E+000
|RECORD=2|OwnerIndex=706|OwnerPartId=1|FormalType=1|PinConglomerate=24|PinLength=30|Location.X=1260|Location.Y=578|Name=84|Designator=84|PinPropagationDelay=0.000000E+000
|RECORD=34|OwnerIndex=706|IndexInSheet=-1|OwnerPartId=-1|Location.X=1200|Location.Y=998|Color=8388608|FontID=1|Text=J35|Name=Designator|ReadOnlyState=1
|RECORD=41|OwnerIndex=706|IndexInSheet=-1|OwnerPartId=-1|Location.X=1200|Location.Y=558|Color=8388608|FontID=1|Text=Single FPGA Conn|Name=Comment
|RECORD=44|OwnerIndex=706
|RECORD=45|OwnerIndex=881|IndexInSheet=-1|ModelName=SingleFPGAConn|ModelType=PCBLIB|DatafileCount=1|ModelDatafileEntity0=SingleFPGAConn|ModelDatafileKind0=PCBLib|IsCurrent=T
|RECORD=46|OwnerIndex=882
|RECORD=48|OwnerIndex=882
|RECORD=1|LibReference=Single FPGA Conn|PartCount=2|DisplayModeCount=1|IndexInSheet=317|OwnerPartId=-1|Location.X=1160|Location.Y=88|CurrentPartId=1|LibraryPath=*|SourceLibraryName=FPGA_CONN.SchLib|TargetFileName=*|AreaColor=11599871|Color=128|PartIDLocked=T|PinsMoveable=T|DesignItemId=Single FPGA Conn|AllPinCount=84
|RECORD=41|OwnerIndex=885|OwnerPartId=-1|Location.X=1155|Location.Y=508|Color=8388608|FontID=1|IsHidden=T|Text=Digi-Key|Name=Supplier 1|ReadOnlyState=3
|RECORD=41|OwnerIndex=885|IndexInSheet=1|OwnerPartId=-1|Location.X=1190|Location.Y=508|Color=8388608|FontID=1|IsHidden=T|Text=255-3246-1-ND|Name=Supplier Part Number 1|ReadOnlyState=3
|RECORD=41|OwnerIndex=885|IndexInSheet=2|OwnerPartId=-1|Location.X=1190|Location.Y=58|Color=8388608|FontID=1|Text=AXK680347YG|Name=Part Number
|RECORD=14|OwnerIndex=885|IsNotAccesible=T|IndexInSheet=3|OwnerPartId=1|Location.X=1190|Location.Y=78|Corner.X=1250|Corner.Y=508|Color=128|AreaColor=11599871|IsSolid=T
|RECORD=2|OwnerIndex=885|OwnerPartId=1|FormalType=1|PinConglomerate=26|PinLength=30|Location.X=1190|Location.Y=498|Name=1|Designator=1|PinPropagationDelay=0.000000E+000
|RECORD=2|OwnerIndex=885|OwnerPartId=1|FormalType=1|PinConglomerate=24|PinLength=30|Location.X=1250|Location.Y=498|Name=2|Designator=2|PinPropagationDelay=0.000000E+000
|RECORD=2|OwnerIndex=885|OwnerPartId=1|FormalType=1|PinConglomerate=26|PinLength=30|Location.X=1190|Location.Y=488|Name=3|Designator=3|PinPropagationDelay=0.000000E+000
|RECORD=2|OwnerIndex=885|OwnerPartId=1|FormalType=1|PinConglomerate=24|PinLength=30|Location.X=1250|Location.Y=488|Name=4|Designator=4|PinPropagationDelay=0.000000E+000
|RECORD=2|OwnerIndex=885|OwnerPartId=1|FormalType=1|PinConglomerate=26|PinLength=30|Location.X=1190|Location.Y=478|Name=5|Designator=5|PinPropagationDelay=0.000000E+000
|RECORD=2|OwnerIndex=885|OwnerPartId=1|FormalType=1|PinConglomerate=24|PinLength=30|Location.X=1250|Location.Y=478|Name=6|Designator=6|PinPropagationDelay=0.000000E+000
|RECORD=2|OwnerIndex=885|OwnerPartId=1|FormalType=1|PinConglomerate=26|PinLength=30|Location.X=1190|Location.Y=468|Name=7|Designator=7|PinPropagationDelay=0.000000E+000
|RECORD=2|OwnerIndex=885|OwnerPartId=1|FormalType=1|PinConglomerate=24|PinLength=30|Location.X=1250|Location.Y=468|Name=8|Designator=8|PinPropagationDelay=0.000000E+000
|RECORD=2|OwnerIndex=885|OwnerPartId=1|FormalType=1|PinConglomerate=26|PinLength=30|Location.X=1190|Location.Y=458|Name=9|Designator=9|PinPropagationDelay=0.000000E+000
|RECORD=2|OwnerIndex=885|OwnerPartId=1|FormalType=1|PinConglomerate=24|PinLength=30|Location.X=1250|Location.Y=458|Name=10|Designator=10|PinPropagationDelay=0.000000E+000
|RECORD=2|OwnerIndex=885|OwnerPartId=1|FormalType=1|PinConglomerate=26|PinLength=30|Location.X=1190|Location.Y=448|Name=11|Designator=11|PinPropagationDelay=0.000000E+000
|RECORD=2|OwnerIndex=885|OwnerPartId=1|FormalType=1|PinConglomerate=24|PinLength=30|Location.X=1250|Location.Y=448|Name=12|Designator=12|PinPropagationDelay=0.000000E+000
|RECORD=2|OwnerIndex=885|OwnerPartId=1|FormalType=1|PinConglomerate=26|PinLength=30|Location.X=1190|Location.Y=438|Name=13|Designator=13|PinPropagationDelay=0.000000E+000
|RECORD=2|OwnerIndex=885|OwnerPartId=1|FormalType=1|PinConglomerate=24|PinLength=30|Location.X=1250|Location.Y=438|Name=14|Designator=14|PinPropagationDelay=0.000000E+000
|RECORD=2|OwnerIndex=885|OwnerPartId=1|FormalType=1|PinConglomerate=26|PinLength=30|Location.X=1190|Location.Y=428|Name=15|Designator=15|PinPropagationDelay=0.000000E+000
|RECORD=2|OwnerIndex=885|OwnerPartId=1|FormalType=1|PinConglomerate=24|PinLength=30|Location.X=1250|Location.Y=428|Name=16|Designator=16|PinPropagationDelay=0.000000E+000
|RECORD=2|OwnerIndex=885|OwnerPartId=1|FormalType=1|PinConglomerate=26|PinLength=30|Location.X=1190|Location.Y=418|Name=17|Designator=17|PinPropagationDelay=0.000000E+000
|RECORD=2|OwnerIndex=885|OwnerPartId=1|FormalType=1|PinConglomerate=24|PinLength=30|Location.X=1250|Location.Y=418|Name=18|Designator=18|PinPropagationDelay=0.000000E+000
|RECORD=2|OwnerIndex=885|OwnerPartId=1|FormalType=1|PinConglomerate=26|PinLength=30|Location.X=1190|Location.Y=408|Name=19|Designator=19|PinPropagationDelay=0.000000E+000
|RECORD=2|OwnerIndex=885|OwnerPartId=1|FormalType=1|PinConglomerate=24|PinLength=30|Location.X=1250|Location.Y=408|Name=20|Designator=20|PinPropagationDelay=0.000000E+000
|RECORD=2|OwnerIndex=885|OwnerPartId=1|FormalType=1|PinConglomerate=26|PinLength=30|Location.X=1190|Location.Y=398|Name=21|Designator=21|PinPropagationDelay=0.000000E+000
|RECORD=2|OwnerIndex=885|OwnerPartId=1|FormalType=1|PinConglomerate=24|PinLength=30|Location.X=1250|Location.Y=398|Name=22|Designator=22|PinPropagationDelay=0.000000E+000
|RECORD=2|OwnerIndex=885|OwnerPartId=1|FormalType=1|PinConglomerate=26|PinLength=30|Location.X=1190|Location.Y=388|Name=23|Designator=23|PinPropagationDelay=0.000000E+000
|RECORD=2|OwnerIndex=885|OwnerPartId=1|FormalType=1|PinConglomerate=24|PinLength=30|Location.X=1250|Location.Y=388|Name=24|Designator=24|PinPropagationDelay=0.000000E+000
|RECORD=2|OwnerIndex=885|OwnerPartId=1|FormalType=1|PinConglomerate=26|PinLength=30|Location.X=1190|Location.Y=378|Name=25|Designator=25|PinPropagationDelay=0.000000E+000
|RECORD=2|OwnerIndex=885|OwnerPartId=1|FormalType=1|PinConglomerate=24|PinLength=30|Location.X=1250|Location.Y=378|Name=26|Designator=26|PinPropagationDelay=0.000000E+000
|RECORD=2|OwnerIndex=885|OwnerPartId=1|FormalType=1|PinConglomerate=26|PinLength=30|Location.X=1190|Location.Y=368|Name=27|Designator=27|PinPropagationDelay=0.000000E+000
|RECORD=2|OwnerIndex=885|OwnerPartId=1|FormalType=1|PinConglomerate=24|PinLength=30|Location.X=1250|Location.Y=368|Name=28|Designator=28|PinPropagationDelay=0.000000E+000
|RECORD=2|OwnerIndex=885|OwnerPartId=1|FormalType=1|PinConglomerate=26|PinLength=30|Location.X=1190|Location.Y=358|Name=29|Designator=29|PinPropagationDelay=0.000000E+000
|RECORD=2|OwnerIndex=885|OwnerPartId=1|FormalType=1|PinConglomerate=24|PinLength=30|Location.X=1250|Location.Y=358|Name=30|Designator=30|PinPropagationDelay=0.000000E+000
|RECORD=2|OwnerIndex=885|OwnerPartId=1|FormalType=1|PinConglomerate=26|PinLength=30|Location.X=1190|Location.Y=348|Name=31|Designator=31|PinPropagationDelay=0.000000E+000
|RECORD=2|OwnerIndex=885|OwnerPartId=1|FormalType=1|PinConglomerate=24|PinLength=30|Location.X=1250|Location.Y=348|Name=32|Designator=32|PinPropagationDelay=0.000000E+000
|RECORD=2|OwnerIndex=885|OwnerPartId=1|FormalType=1|PinConglomerate=26|PinLength=30|Location.X=1190|Location.Y=338|Name=33|Designator=33|PinPropagationDelay=0.000000E+000
|RECORD=2|OwnerIndex=885|OwnerPartId=1|FormalType=1|PinConglomerate=24|PinLength=30|Location.X=1250|Location.Y=338|Name=34|Designator=34|PinPropagationDelay=0.000000E+000
|RECORD=2|OwnerIndex=885|OwnerPartId=1|FormalType=1|PinConglomerate=26|PinLength=30|Location.X=1190|Location.Y=328|Name=35|Designator=35|PinPropagationDelay=0.000000E+000
|RECORD=2|OwnerIndex=885|OwnerPartId=1|FormalType=1|PinConglomerate=24|PinLength=30|Location.X=1250|Location.Y=328|Name=36|Designator=36|PinPropagationDelay=0.000000E+000
|RECORD=2|OwnerIndex=885|OwnerPartId=1|FormalType=1|PinConglomerate=26|PinLength=30|Location.X=1190|Location.Y=318|Name=37|Designator=37|PinPropagationDelay=0.000000E+000
|RECORD=2|OwnerIndex=885|OwnerPartId=1|FormalType=1|PinConglomerate=24|PinLength=30|Location.X=1250|Location.Y=318|Name=38|Designator=38|PinPropagationDelay=0.000000E+000
|RECORD=2|OwnerIndex=885|OwnerPartId=1|FormalType=1|PinConglomerate=26|PinLength=30|Location.X=1190|Location.Y=308|Name=39|Designator=39|PinPropagationDelay=0.000000E+000
|RECORD=2|OwnerIndex=885|OwnerPartId=1|FormalType=1|PinConglomerate=24|PinLength=30|Location.X=1250|Location.Y=308|Name=40|Designator=40|PinPropagationDelay=0.000000E+000
|RECORD=2|OwnerIndex=885|OwnerPartId=1|FormalType=1|PinConglomerate=26|PinLength=30|Location.X=1190|Location.Y=298|Name=41|Designator=41|PinPropagationDelay=0.000000E+000
|RECORD=2|OwnerIndex=885|OwnerPartId=1|FormalType=1|PinConglomerate=24|PinLength=30|Location.X=1250|Location.Y=298|Name=42|Designator=42|PinPropagationDelay=0.000000E+000
|RECORD=2|OwnerIndex=885|OwnerPartId=1|FormalType=1|PinConglomerate=26|PinLength=30|Location.X=1190|Location.Y=288|Name=43|Designator=43|PinPropagationDelay=0.000000E+000
|RECORD=2|OwnerIndex=885|OwnerPartId=1|FormalType=1|PinConglomerate=24|PinLength=30|Location.X=1250|Location.Y=288|Name=44|Designator=44|PinPropagationDelay=0.000000E+000
|RECORD=2|OwnerIndex=885|OwnerPartId=1|FormalType=1|PinConglomerate=26|PinLength=30|Location.X=1190|Location.Y=278|Name=45|Designator=45|PinPropagationDelay=0.000000E+000
|RECORD=2|OwnerIndex=885|OwnerPartId=1|FormalType=1|PinConglomerate=24|PinLength=30|Location.X=1250|Location.Y=278|Name=46|Designator=46|PinPropagationDelay=0.000000E+000
|RECORD=2|OwnerIndex=885|OwnerPartId=1|FormalType=1|PinConglomerate=26|PinLength=30|Location.X=1190|Location.Y=268|Name=47|Designator=47|PinPropagationDelay=0.000000E+000
|RECORD=2|OwnerIndex=885|OwnerPartId=1|FormalType=1|PinConglomerate=24|PinLength=30|Location.X=1250|Location.Y=268|Name=48|Designator=48|PinPropagationDelay=0.000000E+000
|RECORD=2|OwnerIndex=885|OwnerPartId=1|FormalType=1|PinConglomerate=26|PinLength=30|Location.X=1190|Location.Y=258|Name=49|Designator=49|PinPropagationDelay=0.000000E+000
|RECORD=2|OwnerIndex=885|OwnerPartId=1|FormalType=1|PinConglomerate=24|PinLength=30|Location.X=1250|Location.Y=258|Name=50|Designator=50|PinPropagationDelay=0.000000E+000
|RECORD=2|OwnerIndex=885|OwnerPartId=1|FormalType=1|PinConglomerate=26|PinLength=30|Location.X=1190|Location.Y=248|Name=51|Designator=51|PinPropagationDelay=0.000000E+000
|RECORD=2|OwnerIndex=885|OwnerPartId=1|FormalType=1|PinConglomerate=24|PinLength=30|Location.X=1250|Location.Y=248|Name=52|Designator=52|PinPropagationDelay=0.000000E+000
|RECORD=2|OwnerIndex=885|OwnerPartId=1|FormalType=1|PinConglomerate=26|PinLength=30|Location.X=1190|Location.Y=238|Name=53|Designator=53|PinPropagationDelay=0.000000E+000
|RECORD=2|OwnerIndex=885|OwnerPartId=1|FormalType=1|PinConglomerate=24|PinLength=30|Location.X=1250|Location.Y=238|Name=54|Designator=54|PinPropagationDelay=0.000000E+000
|RECORD=2|OwnerIndex=885|OwnerPartId=1|FormalType=1|PinConglomerate=26|PinLength=30|Location.X=1190|Location.Y=228|Name=55|Designator=55|PinPropagationDelay=0.000000E+000
|RECORD=2|OwnerIndex=885|OwnerPartId=1|FormalType=1|PinConglomerate=24|PinLength=30|Location.X=1250|Location.Y=228|Name=56|Designator=56|PinPropagationDelay=0.000000E+000
|RECORD=2|OwnerIndex=885|OwnerPartId=1|FormalType=1|PinConglomerate=26|PinLength=30|Location.X=1190|Location.Y=218|Name=57|Designator=57|PinPropagationDelay=0.000000E+000
|RECORD=2|OwnerIndex=885|OwnerPartId=1|FormalType=1|PinConglomerate=24|PinLength=30|Location.X=1250|Location.Y=218|Name=58|Designator=58|PinPropagationDelay=0.000000E+000
|RECORD=2|OwnerIndex=885|OwnerPartId=1|FormalType=1|PinConglomerate=26|PinLength=30|Location.X=1190|Location.Y=208|Name=59|Designator=59|PinPropagationDelay=0.000000E+000
|RECORD=2|OwnerIndex=885|OwnerPartId=1|FormalType=1|PinConglomerate=24|PinLength=30|Location.X=1250|Location.Y=208|Name=60|Designator=60|PinPropagationDelay=0.000000E+000
|RECORD=2|OwnerIndex=885|OwnerPartId=1|FormalType=1|PinConglomerate=26|PinLength=30|Location.X=1190|Location.Y=198|Name=61|Designator=61|PinPropagationDelay=0.000000E+000
|RECORD=2|OwnerIndex=885|OwnerPartId=1|FormalType=1|PinConglomerate=24|PinLength=30|Location.X=1250|Location.Y=198|Name=62|Designator=62|PinPropagationDelay=0.000000E+000
|RECORD=2|OwnerIndex=885|OwnerPartId=1|FormalType=1|PinConglomerate=26|PinLength=30|Location.X=1190|Location.Y=188|Name=63|Designator=63|PinPropagationDelay=0.000000E+000
|RECORD=2|OwnerIndex=885|OwnerPartId=1|FormalType=1|PinConglomerate=24|PinLength=30|Location.X=1250|Location.Y=188|Name=64|Designator=64|PinPropagationDelay=0.000000E+000
|RECORD=2|OwnerIndex=885|OwnerPartId=1|FormalType=1|PinConglomerate=26|PinLength=30|Location.X=1190|Location.Y=178|Name=65|Designator=65|PinPropagationDelay=0.000000E+000
|RECORD=2|OwnerIndex=885|OwnerPartId=1|FormalType=1|PinConglomerate=24|PinLength=30|Location.X=1250|Location.Y=178|Name=66|Designator=66|PinPropagationDelay=0.000000E+000
|RECORD=2|OwnerIndex=885|OwnerPartId=1|FormalType=1|PinConglomerate=26|PinLength=30|Location.X=1190|Location.Y=168|Name=67|Designator=67|PinPropagationDelay=0.000000E+000
|RECORD=2|OwnerIndex=885|OwnerPartId=1|FormalType=1|PinConglomerate=24|PinLength=30|Location.X=1250|Location.Y=168|Name=68|Designator=68|PinPropagationDelay=0.000000E+000
|RECORD=2|OwnerIndex=885|OwnerPartId=1|FormalType=1|PinConglomerate=26|PinLength=30|Location.X=1190|Location.Y=158|Name=69|Designator=69|PinPropagationDelay=0.000000E+000
|RECORD=2|OwnerIndex=885|OwnerPartId=1|FormalType=1|PinConglomerate=24|PinLength=30|Location.X=1250|Location.Y=158|Name=70|Designator=70|PinPropagationDelay=0.000000E+000
|RECORD=2|OwnerIndex=885|OwnerPartId=1|FormalType=1|PinConglomerate=26|PinLength=30|Location.X=1190|Location.Y=148|Name=71|Designator=71|PinPropagationDelay=0.000000E+000
|RECORD=2|OwnerIndex=885|OwnerPartId=1|FormalType=1|PinConglomerate=24|PinLength=30|Location.X=1250|Location.Y=148|Name=72|Designator=72|PinPropagationDelay=0.000000E+000
|RECORD=2|OwnerIndex=885|OwnerPartId=1|FormalType=1|PinConglomerate=26|PinLength=30|Location.X=1190|Location.Y=138|Name=73|Designator=73|PinPropagationDelay=0.000000E+000
|RECORD=2|OwnerIndex=885|OwnerPartId=1|FormalType=1|PinConglomerate=24|PinLength=30|Location.X=1250|Location.Y=138|Name=74|Designator=74|PinPropagationDelay=0.000000E+000
|RECORD=2|OwnerIndex=885|OwnerPartId=1|FormalType=1|PinConglomerate=26|PinLength=30|Location.X=1190|Location.Y=128|Name=75|Designator=75|PinPropagationDelay=0.000000E+000
|RECORD=2|OwnerIndex=885|OwnerPartId=1|FormalType=1|PinConglomerate=24|PinLength=30|Location.X=1250|Location.Y=128|Name=76|Designator=76|PinPropagationDelay=0.000000E+000
|RECORD=2|OwnerIndex=885|OwnerPartId=1|FormalType=1|PinConglomerate=26|PinLength=30|Location.X=1190|Location.Y=118|Name=77|Designator=77|PinPropagationDelay=0.000000E+000
|RECORD=2|OwnerIndex=885|OwnerPartId=1|FormalType=1|PinConglomerate=24|PinLength=30|Location.X=1250|Location.Y=118|Name=78|Designator=78|PinPropagationDelay=0.000000E+000
|RECORD=2|OwnerIndex=885|OwnerPartId=1|FormalType=1|PinConglomerate=26|PinLength=30|Location.X=1190|Location.Y=108|Name=79|Designator=79|PinPropagationDelay=0.000000E+000
|RECORD=2|OwnerIndex=885|OwnerPartId=1|FormalType=1|PinConglomerate=24|PinLength=30|Location.X=1250|Location.Y=108|Name=80|Designator=80|PinPropagationDelay=0.000000E+000
|RECORD=2|OwnerIndex=885|OwnerPartId=1|FormalType=1|PinConglomerate=26|PinLength=30|Location.X=1190|Location.Y=98|Name=81|Designator=81|PinPropagationDelay=0.000000E+000
|RECORD=2|OwnerIndex=885|OwnerPartId=1|FormalType=1|PinConglomerate=24|PinLength=30|Location.X=1250|Location.Y=98|Name=82|Designator=82|PinPropagationDelay=0.000000E+000
|RECORD=2|OwnerIndex=885|OwnerPartId=1|FormalType=1|PinConglomerate=26|PinLength=30|Location.X=1190|Location.Y=88|Name=83|Designator=83|PinPropagationDelay=0.000000E+000
|RECORD=2|OwnerIndex=885|OwnerPartId=1|FormalType=1|PinConglomerate=24|PinLength=30|Location.X=1250|Location.Y=88|Name=84|Designator=84|PinPropagationDelay=0.000000E+000
|RECORD=34|OwnerIndex=885|IndexInSheet=-1|OwnerPartId=-1|Location.X=1190|Location.Y=508|Color=8388608|FontID=1|Text=J37|Name=Designator|ReadOnlyState=1
|RECORD=41|OwnerIndex=885|IndexInSheet=-1|OwnerPartId=-1|Location.X=1190|Location.Y=68|Color=8388608|FontID=1|Text=Single FPGA Conn|Name=Comment
|RECORD=44|OwnerIndex=885
|RECORD=45|OwnerIndex=1060|IndexInSheet=-1|ModelName=SingleFPGAConn|ModelType=PCBLIB|DatafileCount=1|ModelDatafileEntity0=SingleFPGAConn|ModelDatafileKind0=PCBLib|IsCurrent=T
|RECORD=46|OwnerIndex=1061
|RECORD=48|OwnerIndex=1061
|RECORD=1|LibReference=RES-2|ComponentDescription=Chip Resistor, 0 Ohm, 0.1 W, -55 to 155 degC, 0402 (1005 Metric), RoHS, Tape and Reel|PartCount=2|DisplayModeCount=1|IndexInSheet=318|OwnerPartId=-1|Location.X=1078|Location.Y=828|CurrentPartId=1|LibraryPath=*|SourceLibraryName=Altium Content Vault|TargetFileName=*|AreaColor=11599871|Color=128|PartIDLocked=T|DesignItemId=CMP-2000-07451-1|AllPinCount=2
|RECORD=2|OwnerIndex=1064|OwnerPartId=1|FormalType=1|Electrical=4|PinConglomerate=32|PinLength=10|Location.X=1098|Location.Y=828|Name=2|Designator=2|PinPropagationDelay=0.000000E+000
|RECORD=2|OwnerIndex=1064|OwnerPartId=1|FormalType=1|Electrical=4|PinConglomerate=34|PinLength=10|Location.X=1078|Location.Y=828|Name=1|Designator=1|PinPropagationDelay=0.000000E+000
|RECORD=6|OwnerIndex=1064|IsNotAccesible=T|IndexInSheet=2|OwnerPartId=1|LineWidth=1|Color=16711680|LocationCount=10|X1=1098|Y1=828|X2=1094|Y2=828|X3=1093|Y3=826|X4=1091|Y4=830|X5=1089|Y5=826|X6=1087|Y6=830|X7=1085|Y7=826|X8=1083|Y8=830|X9=1082|Y9=828|X10=1078|Y10=828
|RECORD=41|OwnerIndex=1064|IndexInSheet=3|OwnerPartId=-1|Location.X=1066|Location.Y=843|Color=8388608|FontID=1|IsHidden=T|Text=50V|Name=Voltage Rating (DC)
|RECORD=41|OwnerIndex=1064|IndexInSheet=4|OwnerPartId=-1|Location.X=1066|Location.Y=843|Color=8388608|FontID=1|IsHidden=T|Text=2|Name=Number of Terminations
|RECORD=41|OwnerIndex=1064|IndexInSheet=5|OwnerPartId=-1|Location.X=1066|Location.Y=843|Color=8388608|FontID=1|IsHidden=T|Text=SurfaceMount|Name=Mount
|RECORD=41|OwnerIndex=1064|IndexInSheet=6|OwnerPartId=-1|Location.X=1066|Location.Y=843|Color=8388608|FontID=1|IsHidden=T|Text=0.35mm|Name=Height
|RECORD=41|OwnerIndex=1064|IndexInSheet=7|OwnerPartId=-1|Location.X=1066|Location.Y=843|Color=8388608|FontID=1|IsHidden=T|Text=TapeandReel|Name=Packaging
|RECORD=41|OwnerIndex=1064|IndexInSheet=8|OwnerPartId=-1|Location.X=1066|Location.Y=843|Color=8388608|FontID=1|IsHidden=T|Text=Tin|Name=Contact Plating
|RECORD=41|OwnerIndex=1064|IndexInSheet=9|OwnerPartId=-1|Location.X=1066|Location.Y=843|Color=8388608|FontID=6|IsHidden=T|Text=http://www.panasonic.com/|Name=Manufacturer URL
|RECORD=41|OwnerIndex=1064|IndexInSheet=10|OwnerPartId=-1|Location.X=1066|Location.Y=843|Color=8388608|FontID=1|IsHidden=T|Text=ThickFilm|Name=Composition
|RECORD=41|OwnerIndex=1064|IndexInSheet=11|OwnerPartId=-1|Location.X=1066|Location.Y=843|Color=8388608|FontID=1|IsHidden=T|Text=155degC|Name=Max Operating Temperature
|RECORD=41|OwnerIndex=1064|IndexInSheet=12|OwnerPartId=-1|Location.X=1066|Location.Y=843|Color=8388608|FontID=1|IsHidden=T|Text=600ppm/??C|Name=Temperature Coefficient
|RECORD=41|OwnerIndex=1064|IndexInSheet=13|OwnerPartId=-1|Location.X=1066|Location.Y=843|Color=8388608|FontID=1|IsHidden=T|Text=NoSVHC|Name=REACH SVHC
|RECORD=41|OwnerIndex=1064|IndexInSheet=14|OwnerPartId=-1|Location.X=1066|Location.Y=843|Color=8388608|FontID=1|IsHidden=T|Text=0402|Name=Case/Package
|RECORD=41|OwnerIndex=1064|IndexInSheet=15|OwnerPartId=-1|Location.X=1066|Location.Y=843|Color=8388608|FontID=1|IsHidden=T|Text=100mW|Name=Max Power Dissipation
|RECORD=41|OwnerIndex=1064|IndexInSheet=16|OwnerPartId=-1|Location.X=1066|Location.Y=843|Color=8388608|FontID=1|IsHidden=T|Text=402|Name=Package Reference
|RECORD=41|OwnerIndex=1064|IndexInSheet=17|OwnerPartId=-1|Location.X=1066|Location.Y=843|Color=8388608|FontID=1|IsHidden=T|Text=0.5mm|Name=Depth
|RECORD=41|OwnerIndex=1064|IndexInSheet=18|OwnerPartId=-1|Location.X=1066|Location.Y=843|Color=8388608|FontID=1|IsHidden=T|Text=Panasonic|Name=Manufacturer
|RECORD=41|OwnerIndex=1064|IndexInSheet=19|OwnerPartId=-1|Location.X=1066|Location.Y=843|Color=8388608|FontID=1|IsHidden=T|Text=2-Pin Surface Mount Device, Body 1 x 0.5 mm|Name=Package Description
|RECORD=41|OwnerIndex=1064|IndexInSheet=20|OwnerPartId=-1|Location.X=1066|Location.Y=843|Color=8388608|FontID=6|IsHidden=T|Text=https://industrial.panasonic.com/cdbs/www-data/pdf/RDA0000/AOA0000C301.pdf|Name=Datasheet URL
|RECORD=41|OwnerIndex=1064|IndexInSheet=21|OwnerPartId=-1|Location.X=1066|Location.Y=843|Color=8388608|FontID=1|IsHidden=T|Text=True|Name=RoHSCompliant
|RECORD=41|OwnerIndex=1064|IndexInSheet=22|OwnerPartId=-1|Location.X=1066|Location.Y=843|Color=8388608|FontID=1|IsHidden=T|Text=0402|Name=Case Code (Imperial)
|RECORD=41|OwnerIndex=1064|IndexInSheet=23|OwnerPartId=-1|Location.X=1066|Location.Y=843|Color=8388608|FontID=1|IsHidden=T|Text=0mOhm|Name=Resistance
|RECORD=41|OwnerIndex=1064|IndexInSheet=24|OwnerPartId=-1|Location.X=1066|Location.Y=843|Color=8388608|FontID=1|IsHidden=T|Text=Not|Name=Military Standard
|RECORD=41|OwnerIndex=1064|IndexInSheet=25|OwnerPartId=-1|Location.X=1066|Location.Y=843|Color=8388608|FontID=1|IsHidden=T|Text=5%|Name=Tolerance
|RECORD=41|OwnerIndex=1064|IndexInSheet=26|OwnerPartId=-1|Location.X=1066|Location.Y=843|Color=8388608|FontID=1|IsHidden=T|Text=-55degC|Name=Min Operating Temperature
|RECORD=41|OwnerIndex=1064|IndexInSheet=27|OwnerPartId=-1|Location.X=1066|Location.Y=843|Color=8388608|FontID=1|IsHidden=T|Text=100mW|Name=Power Rating
|RECORD=41|OwnerIndex=1064|IndexInSheet=28|OwnerPartId=-1|Location.X=1066|Location.Y=843|Color=8388608|FontID=1|IsHidden=T|Text=03/2015|Name=Datasheet Version
|RECORD=41|OwnerIndex=1064|IndexInSheet=29|OwnerPartId=-1|Location.X=1066|Location.Y=843|Color=8388608|FontID=1|IsHidden=T|Text=1mm|Name=Length
|RECORD=41|OwnerIndex=1064|IndexInSheet=30|OwnerPartId=-1|Location.X=1066|Location.Y=843|Color=8388608|FontID=1|IsHidden=T|Text=1005|Name=Case Code (Metric)
|RECORD=41|OwnerIndex=1064|IndexInSheet=31|OwnerPartId=-1|Location.X=1066|Location.Y=843|Color=8388608|FontID=1|IsHidden=T|Text=SMD/SMT|Name=Termination
|RECORD=41|OwnerIndex=1064|IndexInSheet=32|OwnerPartId=-1|Location.X=1066|Location.Y=843|Color=8388608|FontID=1|IsHidden=T|Text=SurfaceMount|Name=Mounting Technology
|RECORD=41|OwnerIndex=1064|IndexInSheet=33|OwnerPartId=-1|Location.X=1066|Location.Y=843|Color=8388608|FontID=1|IsHidden=T|Text=50V|Name=Voltage Rating
|RECORD=41|OwnerIndex=1064|IndexInSheet=34|OwnerPartId=-1|Location.X=1066|Location.Y=843|Color=8388608|FontID=1|IsHidden=T|Text=0.02inch|Name=Width
|RECORD=41|OwnerIndex=1064|IndexInSheet=35|OwnerPartId=-1|Location.X=1066|Location.Y=843|Color=8388608|FontID=1|IsHidden=T|Text=1|Name=Package Quantity
|RECORD=41|OwnerIndex=1064|IndexInSheet=36|OwnerPartId=-1|Location.X=1066|Location.Y=843|Color=8388608|FontID=1|IsHidden=T|Text=LeadFree|Name=Lead Free
|RECORD=41|OwnerIndex=1064|IndexInSheet=37|OwnerPartId=-1|Location.X=1066|Location.Y=843|Color=8388608|FontID=1|IsHidden=T|Text=No|Name=Radiation Hardening
|RECORD=34|OwnerIndex=1064|IndexInSheet=-1|OwnerPartId=-1|Location.X=1058|Location.Y=828|Color=8388608|FontID=1|Text=R49|Name=Designator|ReadOnlyState=1
|RECORD=41|OwnerIndex=1064|IndexInSheet=-1|OwnerPartId=-1|Location.X=1098|Location.Y=828|Color=8388608|FontID=1|Text=0_1%_0402|Name=Comment
|RECORD=44|OwnerIndex=1064
|RECORD=45|OwnerIndex=1107|IndexInSheet=-1|Description=Chip Resistor, 2-Leads, Body 1.05x0.55mm, IPC High Density|UseComponentLibrary=T|ModelName=RESC1005X40X25LL05T05|ModelType=PCBLIB|DatafileCount=1|ModelDatafileEntity0=RESC1005X40X25LL05T05|ModelDatafileKind0=PCBLib|IsCurrent=T|DatalinksLocked=T|DatabaseDatalinksLocked=T
|RECORD=46|OwnerIndex=1108
|RECORD=48|OwnerIndex=1108
|RECORD=41|OwnerIndex=1110|IndexInSheet=-1|OwnerPartId=-1|Color=8388608|FontID=1|IsHidden=T|Text=2D|Name=Available Preview Images
|RECORD=45|OwnerIndex=1107|IndexInSheet=-1|Description=Chip Resistor, 2-Leads, Body 1.05x0.55mm, IPC Low Density|UseComponentLibrary=T|ModelName=RESC1005X40X25ML05T05|ModelType=PCBLIB|DatafileCount=1|ModelDatafileEntity0=RESC1005X40X25ML05T05|ModelDatafileKind0=PCBLib|DatalinksLocked=T|DatabaseDatalinksLocked=T
|RECORD=46|OwnerIndex=1112
|RECORD=48|OwnerIndex=1112
|RECORD=41|OwnerIndex=1114|IndexInSheet=-1|OwnerPartId=-1|Color=8388608|FontID=1|IsHidden=T|Text=2D|Name=Available Preview Images
|RECORD=45|OwnerIndex=1107|IndexInSheet=-1|Description=Chip Resistor, 2-Leads, Body 1.05x0.55mm, IPC Medium Density|UseComponentLibrary=T|ModelName=RESC1005X40X25NL05T05|ModelType=PCBLIB|DatafileCount=1|ModelDatafileEntity0=RESC1005X40X25NL05T05|ModelDatafileKind0=PCBLib|DatalinksLocked=T|DatabaseDatalinksLocked=T
|RECORD=46|OwnerIndex=1116
|RECORD=48|OwnerIndex=1116
|RECORD=41|OwnerIndex=1118|IndexInSheet=-1|OwnerPartId=-1|Color=8388608|FontID=1|IsHidden=T|Text=2D|Name=Available Preview Images
|RECORD=17|IndexInSheet=319|OwnerPartId=-1|ShowNetName=T|Location.X=1125|Location.Y=990|Orientation=2|Color=255|FontID=1|Text=GPS1_PIN15|IsCrossSheetConnector=T
|RECORD=17|IndexInSheet=320|OwnerPartId=-1|ShowNetName=T|Location.X=1125|Location.Y=980|Orientation=2|Color=255|FontID=1|Text=GPS1_PIN14|IsCrossSheetConnector=T
|RECORD=17|IndexInSheet=321|OwnerPartId=-1|ShowNetName=T|Location.X=1125|Location.Y=970|Orientation=2|Color=255|FontID=1|Text=GPS1_PIN12|IsCrossSheetConnector=T
|RECORD=17|IndexInSheet=322|OwnerPartId=-1|ShowNetName=T|Location.X=1345|Location.Y=990|Color=255|FontID=1|Text=GPS1_PIN13|IsCrossSheetConnector=T
|RECORD=17|IndexInSheet=323|OwnerPartId=-1|ShowNetName=T|Location.X=1345|Location.Y=980|Color=255|FontID=1|Text=GPS1_PIN11|IsCrossSheetConnector=T
|RECORD=17|IndexInSheet=324|OwnerPartId=-1|ShowNetName=T|Location.X=995|Location.Y=670|Orientation=2|Color=255|FontID=1|Text=GPS2_PIN15|IsCrossSheetConnector=T
|RECORD=17|IndexInSheet=325|OwnerPartId=-1|ShowNetName=T|Location.X=990|Location.Y=630|Orientation=2|Color=255|FontID=1|Text=GPS2_PIN13|IsCrossSheetConnector=T
|RECORD=17|IndexInSheet=326|OwnerPartId=-1|ShowNetName=T|Location.X=990|Location.Y=620|Orientation=2|Color=255|FontID=1|Text=GPS2_PIN11|IsCrossSheetConnector=T
|RECORD=17|IndexInSheet=327|OwnerPartId=-1|ShowNetName=T|Location.X=1415|Location.Y=615|Color=255|FontID=1|Text=GPS2_PIN12|IsCrossSheetConnector=T
|RECORD=17|IndexInSheet=328|OwnerPartId=-1|ShowNetName=T|Location.X=1415|Location.Y=605|Color=255|FontID=1|Text=GPS2_PIN14|IsCrossSheetConnector=T
|RECORD=17|IndexInSheet=329|OwnerPartId=-1|ShowNetName=T|Location.X=995|Location.Y=680|Orientation=2|Color=255|FontID=1|Text=BNO_INT|IsCrossSheetConnector=T
|RECORD=27|IndexInSheet=330|OwnerPartId=-1|LineWidth=1|Color=8388608|LocationCount=2|X1=320|Y1=108|X2=460|Y2=108
|RECORD=27|IndexInSheet=331|OwnerPartId=-1|LineWidth=1|Color=8388608|LocationCount=2|X1=320|Y1=118|X2=460|Y2=118
|RECORD=27|IndexInSheet=332|OwnerPartId=-1|LineWidth=1|Color=8388608|LocationCount=2|X1=320|Y1=388|X2=460|Y2=388
|RECORD=27|IndexInSheet=333|OwnerPartId=-1|LineWidth=1|Color=8388608|LocationCount=2|X1=320|Y1=398|X2=460|Y2=398
|RECORD=27|IndexInSheet=334|OwnerPartId=-1|LineWidth=1|Color=8388608|LocationCount=2|X1=460|Y1=608|X2=330|Y2=608
|RECORD=27|IndexInSheet=335|OwnerPartId=-1|LineWidth=1|Color=8388608|LocationCount=2|X1=460|Y1=618|X2=330|Y2=618
|RECORD=27|IndexInSheet=336|OwnerPartId=-1|LineWidth=1|Color=8388608|LocationCount=2|X1=460|Y1=628|X2=330|Y2=628
|RECORD=27|IndexInSheet=337|OwnerPartId=-1|LineWidth=1|Color=8388608|LocationCount=2|X1=460|Y1=638|X2=330|Y2=638
|RECORD=27|IndexInSheet=338|OwnerPartId=-1|LineWidth=1|Color=8388608|LocationCount=2|X1=460|Y1=658|X2=330|Y2=658
|RECORD=27|IndexInSheet=339|OwnerPartId=-1|LineWidth=1|Color=8388608|LocationCount=2|X1=460|Y1=158|X2=400|Y2=158
|RECORD=27|IndexInSheet=340|OwnerPartId=-1|LineWidth=1|Color=8388608|LocationCount=2|X1=460|Y1=208|X2=400|Y2=208
|RECORD=27|IndexInSheet=341|OwnerPartId=-1|LineWidth=1|Color=8388608|LocationCount=2|X1=460|Y1=258|X2=400|Y2=258
|RECORD=27|IndexInSheet=342|OwnerPartId=-1|LineWidth=1|Color=8388608|LocationCount=2|X1=460|Y1=308|X2=400|Y2=308
|RECORD=27|IndexInSheet=343|OwnerPartId=-1|LineWidth=1|Color=8388608|LocationCount=2|X1=460|Y1=358|X2=400|Y2=358
|RECORD=27|IndexInSheet=344|OwnerPartId=-1|LineWidth=1|Color=8388608|LocationCount=2|X1=460|Y1=408|X2=400|Y2=408
|RECORD=27|IndexInSheet=345|OwnerPartId=-1|LineWidth=1|Color=8388608|LocationCount=9|X1=460|Y1=458|X2=400|Y2=458|X3=400|Y3=408|X4=400|Y4=358|X5=400|Y5=308|X6=400|Y6=258|X7=400|Y7=208|X8=400|Y8=158|X9=400|Y9=68
|RECORD=27|IndexInSheet=346|OwnerPartId=-1|LineWidth=1|Color=8388608|LocationCount=2|X1=460|Y1=648|X2=410|Y2=648
|RECORD=27|IndexInSheet=347|OwnerPartId=-1|LineWidth=1|Color=8388608|LocationCount=2|X1=460|Y1=698|X2=410|Y2=698
|RECORD=27|IndexInSheet=348|OwnerPartId=-1|LineWidth=1|Color=8388608|LocationCount=2|X1=460|Y1=748|X2=410|Y2=748
|RECORD=27|IndexInSheet=349|OwnerPartId=-1|LineWidth=1|Color=8388608|LocationCount=2|X1=460|Y1=798|X2=410|Y2=798
|RECORD=27|IndexInSheet=350|OwnerPartId=-1|LineWidth=1|Color=8388608|LocationCount=2|X1=460|Y1=848|X2=410|Y2=848
|RECORD=27|IndexInSheet=351|OwnerPartId=-1|LineWidth=1|Color=8388608|LocationCount=2|X1=460|Y1=898|X2=410|Y2=898
|RECORD=27|IndexInSheet=352|OwnerPartId=-1|LineWidth=1|Color=8388608|LocationCount=9|X1=460|Y1=948|X2=410|Y2=948|X3=410|Y3=898|X4=410|Y4=848|X5=410|Y5=798|X6=410|Y6=748|X7=410|Y7=698|X8=410|Y8=648|X9=410|Y9=568
|RECORD=27|IndexInSheet=353|OwnerPartId=-1|LineWidth=1|Color=8388608|LocationCount=6|X1=460|Y1=958|X2=410|Y2=958|X3=410|Y3=968|X4=410|Y4=978|X5=410|Y5=988|X6=410|Y6=1008
|RECORD=27|IndexInSheet=354|OwnerPartId=-1|LineWidth=1|Color=8388608|LocationCount=2|X1=460|Y1=968|X2=410|Y2=968
|RECORD=27|IndexInSheet=355|OwnerPartId=-1|LineWidth=1|Color=8388608|LocationCount=2|X1=460|Y1=978|X2=410|Y2=978
|RECORD=27|IndexInSheet=356|OwnerPartId=-1|LineWidth=1|Color=8388608|LocationCount=2|X1=460|Y1=988|X2=410|Y2=988
|RECORD=27|IndexInSheet=357|OwnerPartId=-1|LineWidth=1|Color=8388608|LocationCount=2|X1=580|Y1=108|X2=690|Y2=108
|RECORD=27|IndexInSheet=358|OwnerPartId=-1|LineWidth=1|Color=8388608|LocationCount=2|X1=580|Y1=118|X2=690|Y2=118
|RECORD=27|IndexInSheet=359|OwnerPartId=-1|LineWidth=1|Color=8388608|LocationCount=2|X1=580|Y1=158|X2=620|Y2=158
|RECORD=27|IndexInSheet=360|OwnerPartId=-1|LineWidth=1|Color=8388608|LocationCount=2|X1=580|Y1=208|X2=620|Y2=208
|RECORD=27|IndexInSheet=361|OwnerPartId=-1|LineWidth=1|Color=8388608|LocationCount=2|X1=580|Y1=258|X2=620|Y2=258
|RECORD=27|IndexInSheet=362|OwnerPartId=-1|LineWidth=1|Color=8388608|LocationCount=2|X1=580|Y1=308|X2=620|Y2=308
|RECORD=27|IndexInSheet=363|OwnerPartId=-1|LineWidth=1|Color=8388608|LocationCount=2|X1=580|Y1=358|X2=620|Y2=358
|RECORD=27|IndexInSheet=364|OwnerPartId=-1|LineWidth=1|Color=8388608|LocationCount=2|X1=580|Y1=408|X2=620|Y2=408
|RECORD=27|IndexInSheet=365|OwnerPartId=-1|LineWidth=1|Color=8388608|LocationCount=2|X1=580|Y1=648|X2=600|Y2=648
|RECORD=27|IndexInSheet=366|OwnerPartId=-1|LineWidth=1|Color=8388608|LocationCount=2|X1=580|Y1=698|X2=600|Y2=698
|RECORD=27|IndexInSheet=367|OwnerPartId=-1|LineWidth=1|Color=8388608|LocationCount=2|X1=580|Y1=748|X2=600|Y2=748
|RECORD=27|IndexInSheet=368|OwnerPartId=-1|LineWidth=1|Color=8388608|LocationCount=2|X1=580|Y1=798|X2=600|Y2=798
|RECORD=27|IndexInSheet=369|OwnerPartId=-1|LineWidth=1|Color=8388608|LocationCount=2|X1=640|Y1=828|X2=580|Y2=828
|RECORD=27|IndexInSheet=370|OwnerPartId=-1|LineWidth=1|Color=8388608|LocationCount=2|X1=640|Y1=838|X2=580|Y2=838
|RECORD=27|IndexInSheet=371|OwnerPartId=-1|LineWidth=1|Color=8388608|LocationCount=2|X1=580|Y1=848|X2=600|Y2=848
|RECORD=27|IndexInSheet=372|OwnerPartId=-1|LineWidth=1|Color=8388608|LocationCount=2|X1=640|Y1=888|X2=580|Y2=888
|RECORD=27|IndexInSheet=373|OwnerPartId=-1|LineWidth=1|Color=8388608|LocationCount=2|X1=580|Y1=898|X2=600|Y2=898
|RECORD=27|IndexInSheet=374|OwnerPartId=-1|LineWidth=1|Color=8388608|LocationCount=2|X1=580|Y1=968|X2=600|Y2=968
|RECORD=27|IndexInSheet=375|OwnerPartId=-1|LineWidth=1|Color=8388608|LocationCount=2|X1=580|Y1=978|X2=600|Y2=978
|RECORD=27|IndexInSheet=376|OwnerPartId=-1|LineWidth=1|Color=8388608|LocationCount=2|X1=580|Y1=988|X2=600|Y2=988
|RECORD=27|IndexInSheet=377|OwnerPartId=-1|LineWidth=1|Color=8388608|LocationCount=2|X1=1160|Y1=318|X2=1060|Y2=318
|RECORD=27|IndexInSheet=378|OwnerPartId=-1|LineWidth=1|Color=8388608|LocationCount=2|X1=1160|Y1=328|X2=1060|Y2=328
|RECORD=27|IndexInSheet=379|OwnerPartId=-1|LineWidth=1|Color=8388608|LocationCount=2|X1=1160|Y1=348|X2=1060|Y2=348
|RECORD=27|IndexInSheet=380|OwnerPartId=-1|LineWidth=1|Color=8388608|LocationCount=2|X1=1160|Y1=358|X2=1060|Y2=358
|RECORD=27|IndexInSheet=381|OwnerPartId=-1|LineWidth=1|Color=8388608|LocationCount=2|X1=1160|Y1=378|X2=1060|Y2=378
|RECORD=27|IndexInSheet=382|OwnerPartId=-1|LineWidth=1|Color=8388608|LocationCount=2|X1=1160|Y1=388|X2=1060|Y2=388
|RECORD=27|IndexInSheet=383|OwnerPartId=-1|LineWidth=1|Color=8388608|LocationCount=2|X1=1160|Y1=408|X2=1060|Y2=408
|RECORD=27|IndexInSheet=384|OwnerPartId=-1|LineWidth=1|Color=8388608|LocationCount=2|X1=1160|Y1=418|X2=1060|Y2=418
|RECORD=27|IndexInSheet=385|OwnerPartId=-1|LineWidth=1|Color=8388608|LocationCount=2|X1=1170|Y1=598|X2=1060|Y2=598
|RECORD=27|IndexInSheet=386|OwnerPartId=-1|LineWidth=1|Color=8388608|LocationCount=2|X1=1060|Y1=658|X2=1170|Y2=658
|RECORD=27|IndexInSheet=387|OwnerPartId=-1|LineWidth=1|Color=8388608|LocationCount=2|X1=1060|Y1=688|X2=1170|Y2=688
|RECORD=27|IndexInSheet=388|OwnerPartId=-1|LineWidth=1|Color=8388608|LocationCount=2|X1=1060|Y1=758|X2=1170|Y2=758
|RECORD=27|IndexInSheet=389|OwnerPartId=-1|LineWidth=1|Color=8388608|LocationCount=2|X1=1060|Y1=778|X2=1170|Y2=778
|RECORD=27|IndexInSheet=390|OwnerPartId=-1|LineWidth=1|Color=8388608|LocationCount=2|X1=1170|Y1=808|X2=1060|Y2=808
|RECORD=27|IndexInSheet=391|OwnerPartId=-1|LineWidth=1|Color=8388608|LocationCount=2|X1=1170|Y1=818|X2=1060|Y2=818
|RECORD=27|IndexInSheet=392|OwnerPartId=-1|LineWidth=1|Color=8388608|LocationCount=2|X1=1059|Y1=858|X2=1170|Y2=858
|RECORD=27|IndexInSheet=393|OwnerPartId=-1|LineWidth=1|Color=8388608|LocationCount=2|X1=1059|Y1=868|X2=1170|Y2=868
|RECORD=27|IndexInSheet=394|OwnerPartId=-1|LineWidth=1|Color=8388608|LocationCount=2|X1=1059|Y1=878|X2=1170|Y2=878
|RECORD=27|IndexInSheet=395|OwnerPartId=-1|LineWidth=1|Color=8388608|LocationCount=2|X1=1059|Y1=888|X2=1170|Y2=888
|RECORD=27|IndexInSheet=396|OwnerPartId=-1|LineWidth=1|Color=8388608|LocationCount=3|X1=1060|Y1=938|X2=1160|Y2=938|X3=1170|Y3=938
|RECORD=27|IndexInSheet=397|OwnerPartId=-1|LineWidth=1|Color=8388608|LocationCount=2|X1=1160|Y1=158|X2=1110|Y2=158
|RECORD=27|IndexInSheet=398|OwnerPartId=-1|LineWidth=1|Color=8388608|LocationCount=2|X1=1160|Y1=208|X2=1110|Y2=208
|RECORD=27|IndexInSheet=399|OwnerPartId=-1|LineWidth=1|Color=8388608|LocationCount=2|X1=1160|Y1=258|X2=1110|Y2=258
|RECORD=27|IndexInSheet=400|OwnerPartId=-1|LineWidth=1|Color=8388608|LocationCount=2|X1=1160|Y1=308|X2=1110|Y2=308
|RECORD=27|IndexInSheet=401|OwnerPartId=-1|LineWidth=1|Color=8388608|LocationCount=2|X1=1160|Y1=338|X2=1110|Y2=338
|RECORD=27|IndexInSheet=402|OwnerPartId=-1|LineWidth=1|Color=8388608|LocationCount=2|X1=1160|Y1=368|X2=1110|Y2=368
|RECORD=27|IndexInSheet=403|OwnerPartId=-1|LineWidth=1|Color=8388608|LocationCount=2|X1=1160|Y1=398|X2=1110|Y2=398
|RECORD=27|IndexInSheet=404|OwnerPartId=-1|LineWidth=1|Color=8388608|LocationCount=2|X1=1160|Y1=428|X2=1110|Y2=428
|RECORD=27|IndexInSheet=405|OwnerPartId=-1|LineWidth=1|Color=8388608|LocationCount=11|X1=1160|Y1=458|X2=1110|Y2=458|X3=1110|Y3=428|X4=1110|Y4=398|X5=1110|Y5=368|X6=1110|Y6=338|X7=1110|Y7=308|X8=1110|Y8=258|X9=1110|Y9=208|X10=1110|Y10=158|X11=1110|Y11=78
|RECORD=27|IndexInSheet=406|OwnerPartId=-1|LineWidth=1|Color=8388608|LocationCount=2|X1=1170|Y1=648|X2=1130|Y2=648
|RECORD=27|IndexInSheet=407|OwnerPartId=-1|LineWidth=1|Color=8388608|LocationCount=2|X1=1170|Y1=698|X2=1130|Y2=698
|RECORD=27|IndexInSheet=408|OwnerPartId=-1|LineWidth=1|Color=8388608|LocationCount=2|X1=1170|Y1=748|X2=1130|Y2=748
|RECORD=27|IndexInSheet=409|OwnerPartId=-1|LineWidth=1|Color=8388608|LocationCount=2|X1=1170|Y1=798|X2=1130|Y2=798
|RECORD=27|IndexInSheet=410|OwnerPartId=-1|LineWidth=1|Color=8388608|LocationCount=2|X1=1170|Y1=848|X2=1130|Y2=848
|RECORD=27|IndexInSheet=411|OwnerPartId=-1|LineWidth=1|Color=8388608|LocationCount=2|X1=1170|Y1=898|X2=1130|Y2=898
|RECORD=27|IndexInSheet=412|OwnerPartId=-1|LineWidth=1|Color=8388608|LocationCount=9|X1=1170|Y1=948|X2=1130|Y2=948|X3=1130|Y3=898|X4=1130|Y4=848|X5=1130|Y5=798|X6=1130|Y6=748|X7=1130|Y7=698|X8=1130|Y8=648|X9=1130|Y9=568
|RECORD=27|IndexInSheet=413|OwnerPartId=-1|LineWidth=1|Color=8388608|LocationCount=3|X1=1170|Y1=928|X2=1160|Y2=928|X3=1160|Y3=938
|RECORD=27|IndexInSheet=414|OwnerPartId=-1|LineWidth=1|Color=8388608|LocationCount=2|X1=1280|Y1=158|X2=1310|Y2=158
|RECORD=27|IndexInSheet=415|OwnerPartId=-1|LineWidth=1|Color=8388608|LocationCount=2|X1=1280|Y1=208|X2=1310|Y2=208
|RECORD=27|IndexInSheet=416|OwnerPartId=-1|LineWidth=1|Color=8388608|LocationCount=2|X1=1280|Y1=258|X2=1310|Y2=258
|RECORD=27|IndexInSheet=417|OwnerPartId=-1|LineWidth=1|Color=8388608|LocationCount=2|X1=1280|Y1=308|X2=1310|Y2=308
|RECORD=27|IndexInSheet=418|OwnerPartId=-1|LineWidth=1|Color=8388608|LocationCount=2|X1=1280|Y1=318|X2=1360|Y2=318
|RECORD=27|IndexInSheet=419|OwnerPartId=-1|LineWidth=1|Color=8388608|LocationCount=2|X1=1280|Y1=328|X2=1360|Y2=328
|RECORD=27|IndexInSheet=420|OwnerPartId=-1|LineWidth=1|Color=8388608|LocationCount=2|X1=1280|Y1=348|X2=1360|Y2=348
|RECORD=27|IndexInSheet=421|OwnerPartId=-1|LineWidth=1|Color=8388608|LocationCount=2|X1=1280|Y1=358|X2=1360|Y2=358
|RECORD=27|IndexInSheet=422|OwnerPartId=-1|LineWidth=1|Color=8388608|LocationCount=2|X1=1280|Y1=378|X2=1360|Y2=378
|RECORD=27|IndexInSheet=423|OwnerPartId=-1|LineWidth=1|Color=8388608|LocationCount=2|X1=1280|Y1=388|X2=1360|Y2=388
|RECORD=27|IndexInSheet=424|OwnerPartId=-1|LineWidth=1|Color=8388608|LocationCount=2|X1=1280|Y1=408|X2=1360|Y2=408
|RECORD=27|IndexInSheet=425|OwnerPartId=-1|LineWidth=1|Color=8388608|LocationCount=2|X1=1280|Y1=418|X2=1360|Y2=418
|RECORD=27|IndexInSheet=426|OwnerPartId=-1|LineWidth=1|Color=8388608|LocationCount=2|X1=1280|Y1=438|X2=1360|Y2=438
|RECORD=27|IndexInSheet=427|OwnerPartId=-1|LineWidth=1|Color=8388608|LocationCount=2|X1=1280|Y1=448|X2=1360|Y2=448
|RECORD=27|IndexInSheet=428|OwnerPartId=-1|LineWidth=1|Color=8388608|LocationCount=2|X1=1290|Y1=648|X2=1320|Y2=648
|RECORD=27|IndexInSheet=429|OwnerPartId=-1|LineWidth=1|Color=8388608|LocationCount=2|X1=1290|Y1=698|X2=1320|Y2=698
|RECORD=27|IndexInSheet=430|OwnerPartId=-1|LineWidth=1|Color=8388608|LocationCount=2|X1=1290|Y1=748|X2=1320|Y2=748
|RECORD=27|IndexInSheet=431|OwnerPartId=-1|LineWidth=1|Color=8388608|LocationCount=2|X1=1290|Y1=798|X2=1320|Y2=798
|RECORD=27|IndexInSheet=432|OwnerPartId=-1|LineWidth=1|Color=8388608|LocationCount=2|X1=1290|Y1=848|X2=1320|Y2=848
|RECORD=27|IndexInSheet=433|OwnerPartId=-1|LineWidth=1|Color=8388608|LocationCount=2|X1=1290|Y1=898|X2=1320|Y2=898
|RECORD=27|IndexInSheet=434|OwnerPartId=-1|LineWidth=1|Color=8388608|LocationCount=2|X1=1350|Y1=958|X2=1290|Y2=958
|RECORD=27|IndexInSheet=435|OwnerPartId=-1|LineWidth=1|Color=8388608|LocationCount=9|X1=580|Y1=948|X2=600|Y2=948|X3=600|Y3=898|X4=600|Y4=848|X5=600|Y5=798|X6=600|Y6=748|X7=600|Y7=698|X8=600|Y8=648|X9=600|Y9=568
|RECORD=27|IndexInSheet=436|OwnerPartId=-1|LineWidth=1|Color=8388608|LocationCount=6|X1=580|Y1=958|X2=600|Y2=958|X3=600|Y3=968|X4=600|Y4=978|X5=600|Y5=988|X6=600|Y6=1008
|RECORD=27|IndexInSheet=437|OwnerPartId=-1|LineWidth=1|Color=8388608|LocationCount=2|X1=1290|Y1=598|X2=1350|Y2=598
|RECORD=27|IndexInSheet=438|OwnerPartId=-1|LineWidth=1|Color=8388608|LocationCount=2|X1=1350|Y1=628|X2=1290|Y2=628
|RECORD=27|IndexInSheet=439|OwnerPartId=-1|LineWidth=1|Color=8388608|LocationCount=2|X1=1350|Y1=638|X2=1290|Y2=638
|RECORD=27|IndexInSheet=440|OwnerPartId=-1|LineWidth=1|Color=8388608|LocationCount=2|X1=1350|Y1=858|X2=1290|Y2=858
|RECORD=27|IndexInSheet=441|OwnerPartId=-1|LineWidth=1|Color=8388608|LocationCount=2|X1=1350|Y1=868|X2=1290|Y2=868
|RECORD=27|IndexInSheet=442|OwnerPartId=-1|LineWidth=1|Color=8388608|LocationCount=9|X1=580|Y1=458|X2=620|Y2=458|X3=620|Y3=408|X4=620|Y4=358|X5=620|Y5=308|X6=620|Y6=258|X7=620|Y7=208|X8=620|Y8=158|X9=620|Y9=68
|RECORD=27|IndexInSheet=443|OwnerPartId=-1|LineWidth=1|Color=8388608|LocationCount=7|X1=1280|Y1=458|X2=1310|Y2=458|X3=1310|Y3=308|X4=1310|Y4=258|X5=1310|Y5=208|X6=1310|Y6=158|X7=1310|Y7=78
|RECORD=27|IndexInSheet=444|OwnerPartId=-1|LineWidth=1|Color=8388608|LocationCount=2|X1=1170|Y1=728|X2=1060|Y2=728
|RECORD=27|IndexInSheet=445|OwnerPartId=-1|LineWidth=1|Color=8388608|LocationCount=2|X1=460|Y1=498|X2=318|Y2=498
|RECORD=27|IndexInSheet=446|OwnerPartId=-1|LineWidth=1|Color=8388608|LocationCount=2|X1=580|Y1=498|X2=690|Y2=498
|RECORD=27|IndexInSheet=447|OwnerPartId=-1|LineWidth=1|Color=8388608|LocationCount=2|X1=1170|Y1=608|X2=1060|Y2=608
|RECORD=27|IndexInSheet=448|OwnerPartId=-1|LineWidth=1|Color=8388608|LocationCount=2|X1=1170|Y1=638|X2=1061|Y2=638
|RECORD=27|IndexInSheet=449|OwnerPartId=-1|LineWidth=1|Color=8388608|LocationCount=2|X1=460|Y1=478|X2=319|Y2=478
|RECORD=27|IndexInSheet=450|OwnerPartId=-1|LineWidth=1|Color=8388608|LocationCount=2|X1=460|Y1=448|X2=319|Y2=448
|RECORD=27|IndexInSheet=451|OwnerPartId=-1|LineWidth=1|Color=8388608|LocationCount=2|X1=460|Y1=468|X2=319|Y2=468
|RECORD=27|IndexInSheet=452|OwnerPartId=-1|LineWidth=1|Color=8388608|LocationCount=2|X1=580|Y1=448|X2=690|Y2=448
|RECORD=27|IndexInSheet=453|OwnerPartId=-1|LineWidth=1|Color=8388608|LocationCount=2|X1=580|Y1=438|X2=690|Y2=438
|RECORD=27|IndexInSheet=454|OwnerPartId=-1|LineWidth=1|Color=8388608|LocationCount=2|X1=580|Y1=428|X2=690|Y2=428
|RECORD=27|IndexInSheet=455|OwnerPartId=-1|LineWidth=1|Color=8388608|LocationCount=2|X1=691|Y1=418|X2=580|Y2=418
|RECORD=27|IndexInSheet=456|OwnerPartId=-1|LineWidth=1|Color=8388608|LocationCount=2|X1=1170|Y1=918|X2=1059|Y2=918
|RECORD=27|IndexInSheet=457|OwnerPartId=-1|LineWidth=1|Color=8388608|LocationCount=2|X1=1170|Y1=908|X2=1059|Y2=908
|RECORD=27|IndexInSheet=458|OwnerPartId=-1|LineWidth=1|Color=8388608|LocationCount=2|X1=1290|Y1=918|X2=1352|Y2=918
|RECORD=27|IndexInSheet=459|OwnerPartId=-1|LineWidth=1|Color=8388608|LocationCount=2|X1=1290|Y1=908|X2=1352|Y2=908
|RECORD=27|IndexInSheet=460|OwnerPartId=-1|LineWidth=1|Color=8388608|LocationCount=2|X1=320|Y1=338|X2=460|Y2=338
|RECORD=27|IndexInSheet=461|OwnerPartId=-1|LineWidth=1|Color=8388608|LocationCount=2|X1=320|Y1=348|X2=460|Y2=348
|RECORD=27|IndexInSheet=462|OwnerPartId=-1|LineWidth=1|Color=8388608|LocationCount=2|X1=320|Y1=328|X2=460|Y2=328
|RECORD=27|IndexInSheet=463|OwnerPartId=-1|LineWidth=1|Color=8388608|LocationCount=2|X1=320|Y1=318|X2=460|Y2=318
|RECORD=27|IndexInSheet=464|OwnerPartId=-1|LineWidth=1|Color=8388608|LocationCount=2|X1=320|Y1=298|X2=460|Y2=298
|RECORD=27|IndexInSheet=465|OwnerPartId=-1|LineWidth=1|Color=8388608|LocationCount=2|X1=320|Y1=288|X2=460|Y2=288
|RECORD=27|IndexInSheet=466|OwnerPartId=-1|LineWidth=1|Color=8388608|LocationCount=2|X1=460|Y1=278|X2=320|Y2=278
|RECORD=27|IndexInSheet=467|OwnerPartId=-1|LineWidth=1|Color=8388608|LocationCount=2|X1=320|Y1=268|X2=460|Y2=268
|RECORD=27|IndexInSheet=468|OwnerPartId=-1|LineWidth=1|Color=8388608|LocationCount=2|X1=691|Y1=348|X2=580|Y2=348
|RECORD=27|IndexInSheet=469|OwnerPartId=-1|LineWidth=1|Color=8388608|LocationCount=2|X1=691|Y1=338|X2=580|Y2=338
|RECORD=27|IndexInSheet=470|OwnerPartId=-1|LineWidth=1|Color=8388608|LocationCount=2|X1=691|Y1=328|X2=580|Y2=328
|RECORD=27|IndexInSheet=471|OwnerPartId=-1|LineWidth=1|Color=8388608|LocationCount=2|X1=691|Y1=318|X2=580|Y2=318
|RECORD=27|IndexInSheet=472|OwnerPartId=-1|LineWidth=1|Color=8388608|LocationCount=2|X1=691|Y1=298|X2=580|Y2=298
|RECORD=27|IndexInSheet=473|OwnerPartId=-1|LineWidth=1|Color=8388608|LocationCount=2|X1=691|Y1=288|X2=580|Y2=288
|RECORD=27|IndexInSheet=474|OwnerPartId=-1|LineWidth=1|Color=8388608|LocationCount=2|X1=691|Y1=278|X2=580|Y2=278
|RECORD=27|IndexInSheet=475|OwnerPartId=-1|LineWidth=1|Color=8388608|LocationCount=2|X1=691|Y1=268|X2=580|Y2=268
|RECORD=27|IndexInSheet=476|OwnerPartId=-1|LineWidth=1|Color=8388608|LocationCount=2|X1=691|Y1=778|X2=580|Y2=778
|RECORD=27|IndexInSheet=477|OwnerPartId=-1|LineWidth=1|Color=8388608|LocationCount=9|X1=1290|Y1=948|X2=1320|Y2=948|X3=1320|Y3=898|X4=1320|Y4=848|X5=1320|Y5=798|X6=1320|Y6=748|X7=1320|Y7=698|X8=1320|Y8=648|X9=1320|Y9=568
|RECORD=27|IndexInSheet=478|OwnerPartId=-1|LineWidth=1|Color=8388608|LocationCount=2|X1=1060|Y1=828|X2=1068|Y2=828
|RECORD=27|IndexInSheet=479|OwnerPartId=-1|LineWidth=1|Color=8388608|LocationCount=2|X1=1170|Y1=828|X2=1108|Y2=828
|RECORD=27|IndexInSheet=480|OwnerPartId=-1|LineWidth=1|Color=8388608|LocationCount=4|X1=1170|Y1=968|X2=1135|Y2=968|X3=1135|Y3=970|X4=1125|Y4=970
|RECORD=27|IndexInSheet=481|OwnerPartId=-1|LineWidth=1|Color=8388608|LocationCount=4|X1=1170|Y1=978|X2=1140|Y2=978|X3=1140|Y3=980|X4=1125|Y4=980
|RECORD=27|IndexInSheet=482|OwnerPartId=-1|LineWidth=1|Color=8388608|LocationCount=4|X1=1170|Y1=988|X2=1145|Y2=988|X3=1145|Y3=990|X4=1125|Y4=990
|RECORD=27|IndexInSheet=483|OwnerPartId=-1|LineWidth=1|Color=8388608|LocationCount=4|X1=1290|Y1=978|X2=1315|Y2=978|X3=1315|Y3=980|X4=1345|Y4=980
|RECORD=27|IndexInSheet=484|OwnerPartId=-1|LineWidth=1|Color=8388608|LocationCount=4|X1=1290|Y1=988|X2=1310|Y2=988|X3=1310|Y3=990|X4=1345|Y4=990
|RECORD=27|IndexInSheet=485|OwnerPartId=-1|LineWidth=1|Color=8388608|LocationCount=4|X1=1290|Y1=608|X2=1395|Y2=608|X3=1395|Y3=605|X4=1415|Y4=605
|RECORD=27|IndexInSheet=486|OwnerPartId=-1|LineWidth=1|Color=8388608|LocationCount=4|X1=1290|Y1=618|X2=1380|Y2=618|X3=1380|Y3=615|X4=1415|Y4=615
|RECORD=27|IndexInSheet=487|OwnerPartId=-1|LineWidth=1|Color=8388608|LocationCount=4|X1=1170|Y1=668|X2=1025|Y2=668|X3=1025|Y3=670|X4=995|Y4=670
|RECORD=27|IndexInSheet=488|OwnerPartId=-1|LineWidth=1|Color=8388608|LocationCount=4|X1=1170|Y1=618|X2=1005|Y2=618|X3=1005|Y3=620|X4=990|Y4=620
|RECORD=27|IndexInSheet=489|OwnerPartId=-1|LineWidth=1|Color=8388608|LocationCount=4|X1=1170|Y1=628|X2=1035|Y2=628|X3=1035|Y3=630|X4=990|Y4=630
|RECORD=27|IndexInSheet=490|OwnerPartId=-1|LineWidth=1|Color=8388608|LocationCount=4|X1=1170|Y1=718|X2=1150|Y2=718|X3=1150|Y3=715|X4=1060|Y4=715
|RECORD=27|IndexInSheet=491|OwnerPartId=-1|LineWidth=1|Color=8388608|LocationCount=4|X1=1170|Y1=708|X2=1160|Y2=708|X3=1160|Y3=705|X4=1060|Y4=705
|RECORD=27|IndexInSheet=492|OwnerPartId=-1|LineWidth=1|Color=8388608|LocationCount=4|X1=1170|Y1=678|X2=1015|Y2=678|X3=1015|Y3=680|X4=995|Y4=680
|RECORD=17|IndexInSheet=493|OwnerPartId=-1|Style=1|ShowNetName=T|Location.X=1060|Location.Y=705|Orientation=2|Color=255|FontID=1|Text=BNO_XOUT32_C|IsCrossSheetConnector=T
|RECORD=17|IndexInSheet=494|OwnerPartId=-1|Style=1|ShowNetName=T|Location.X=1060|Location.Y=715|Orientation=2|Color=255|FontID=1|Text=BNO_XIN32_C|IsCrossSheetConnector=T
|RECORD=29|IndexInSheet=-1|OwnerPartId=-1|Location.X=400|Location.Y=158|Color=128
|RECORD=29|IndexInSheet=-1|OwnerPartId=-1|Location.X=400|Location.Y=208|Color=128
|RECORD=29|IndexInSheet=-1|OwnerPartId=-1|Location.X=400|Location.Y=258|Color=128
|RECORD=29|IndexInSheet=-1|OwnerPartId=-1|Location.X=400|Location.Y=308|Color=128
|RECORD=29|IndexInSheet=-1|OwnerPartId=-1|Location.X=400|Location.Y=358|Color=128
|RECORD=29|IndexInSheet=-1|OwnerPartId=-1|Location.X=400|Location.Y=408|Color=128
|RECORD=29|IndexInSheet=-1|OwnerPartId=-1|Location.X=410|Location.Y=648|Color=128
|RECORD=29|IndexInSheet=-1|OwnerPartId=-1|Location.X=410|Location.Y=698|Color=128
|RECORD=29|IndexInSheet=-1|OwnerPartId=-1|Location.X=410|Location.Y=748|Color=128
|RECORD=29|IndexInSheet=-1|OwnerPartId=-1|Location.X=410|Location.Y=798|Color=128
|RECORD=29|IndexInSheet=-1|OwnerPartId=-1|Location.X=410|Location.Y=848|Color=128
|RECORD=29|IndexInSheet=-1|OwnerPartId=-1|Location.X=410|Location.Y=898|Color=128
|RECORD=29|IndexInSheet=-1|OwnerPartId=-1|Location.X=410|Location.Y=968|Color=128
|RECORD=29|IndexInSheet=-1|OwnerPartId=-1|Location.X=410|Location.Y=978|Color=128
|RECORD=29|IndexInSheet=-1|OwnerPartId=-1|Location.X=410|Location.Y=988|Color=128
|RECORD=29|IndexInSheet=-1|OwnerPartId=-1|Location.X=600|Location.Y=648|Color=128
|RECORD=29|IndexInSheet=-1|OwnerPartId=-1|Location.X=600|Location.Y=698|Color=128
|RECORD=29|IndexInSheet=-1|OwnerPartId=-1|Location.X=600|Location.Y=748|Color=128
|RECORD=29|IndexInSheet=-1|OwnerPartId=-1|Location.X=600|Location.Y=798|Color=128
|RECORD=29|IndexInSheet=-1|OwnerPartId=-1|Location.X=600|Location.Y=848|Color=128
|RECORD=29|IndexInSheet=-1|OwnerPartId=-1|Location.X=600|Location.Y=898|Color=128
|RECORD=29|IndexInSheet=-1|OwnerPartId=-1|Location.X=600|Location.Y=968|Color=128
|RECORD=29|IndexInSheet=-1|OwnerPartId=-1|Location.X=600|Location.Y=978|Color=128
|RECORD=29|IndexInSheet=-1|OwnerPartId=-1|Location.X=600|Location.Y=988|Color=128
|RECORD=29|IndexInSheet=-1|OwnerPartId=-1|Location.X=620|Location.Y=158|Color=128
|RECORD=29|IndexInSheet=-1|OwnerPartId=-1|Location.X=620|Location.Y=208|Color=128
|RECORD=29|IndexInSheet=-1|OwnerPartId=-1|Location.X=620|Location.Y=258|Color=128
|RECORD=29|IndexInSheet=-1|OwnerPartId=-1|Location.X=620|Location.Y=308|Color=128
|RECORD=29|IndexInSheet=-1|OwnerPartId=-1|Location.X=620|Location.Y=358|Color=128
|RECORD=29|IndexInSheet=-1|OwnerPartId=-1|Location.X=620|Location.Y=408|Color=128
|RECORD=29|IndexInSheet=-1|OwnerPartId=-1|Location.X=1110|Location.Y=158|Color=128
|RECORD=29|IndexInSheet=-1|OwnerPartId=-1|Location.X=1110|Location.Y=208|Color=128
|RECORD=29|IndexInSheet=-1|OwnerPartId=-1|Location.X=1110|Location.Y=258|Color=128
|RECORD=29|IndexInSheet=-1|OwnerPartId=-1|Location.X=1110|Location.Y=308|Color=128
|RECORD=29|IndexInSheet=-1|OwnerPartId=-1|Location.X=1110|Location.Y=338|Color=128
|RECORD=29|IndexInSheet=-1|OwnerPartId=-1|Location.X=1110|Location.Y=368|Color=128
|RECORD=29|IndexInSheet=-1|OwnerPartId=-1|Location.X=1110|Location.Y=398|Color=128
|RECORD=29|IndexInSheet=-1|OwnerPartId=-1|Location.X=1110|Location.Y=428|Color=128
|RECORD=29|IndexInSheet=-1|OwnerPartId=-1|Location.X=1130|Location.Y=648|Color=128
|RECORD=29|IndexInSheet=-1|OwnerPartId=-1|Location.X=1130|Location.Y=698|Color=128
|RECORD=29|IndexInSheet=-1|OwnerPartId=-1|Location.X=1130|Location.Y=748|Color=128
|RECORD=29|IndexInSheet=-1|OwnerPartId=-1|Location.X=1130|Location.Y=798|Color=128
|RECORD=29|IndexInSheet=-1|OwnerPartId=-1|Location.X=1130|Location.Y=848|Color=128
|RECORD=29|IndexInSheet=-1|OwnerPartId=-1|Location.X=1130|Location.Y=898|Color=128
|RECORD=29|IndexInSheet=-1|OwnerPartId=-1|Location.X=1160|Location.Y=938|Color=128
|RECORD=29|IndexInSheet=-1|OwnerPartId=-1|Location.X=1310|Location.Y=158|Color=128
|RECORD=29|IndexInSheet=-1|OwnerPartId=-1|Location.X=1310|Location.Y=208|Color=128
|RECORD=29|IndexInSheet=-1|OwnerPartId=-1|Location.X=1310|Location.Y=258|Color=128
|RECORD=29|IndexInSheet=-1|OwnerPartId=-1|Location.X=1310|Location.Y=308|Color=128
|RECORD=29|IndexInSheet=-1|OwnerPartId=-1|Location.X=1320|Location.Y=648|Color=128
|RECORD=29|IndexInSheet=-1|OwnerPartId=-1|Location.X=1320|Location.Y=698|Color=128
|RECORD=29|IndexInSheet=-1|OwnerPartId=-1|Location.X=1320|Location.Y=748|Color=128
|RECORD=29|IndexInSheet=-1|OwnerPartId=-1|Location.X=1320|Location.Y=798|Color=128
|RECORD=29|IndexInSheet=-1|OwnerPartId=-1|Location.X=1320|Location.Y=848|Color=128
|RECORD=29|IndexInSheet=-1|OwnerPartId=-1|Location.X=1320|Location.Y=898|Color=128